FILE_TYPE = MACRO_DRAWING;
SET COLOR_WIRE YELLOW;
SET COLOR_PROP ORANGE;
SET COLOR_DOT WHITE;
SET COLOR_ARC YELLOW;
SET COLOR_BODY GREEN;
SET COLOR_NOTE PURPLE;
SET PROP_DISPLAY VALUE;
SET PAGE_NUMBER P51;
FORCEADD GENOA_SP5..15
(-4700 4750);
FORCEPROP 1 LAST LOCATION U26
J 0
(-5795 6006);
DISPLAY 0.489362 (-5795 6006);
PAINT SKYBLUE (-5795 6006);
FORCEPROP 0 LAST $SEC 15
J 0
(-5775 6050);
DISPLAY 0.680851 (-5775 6050);
PAINT MONO (-5775 6050);
DISPLAY INVISIBLE (-5775 6050);
FORCEPROP 0 LAST CDS_SEC 15
J 0
(-5800 6000);
DISPLAY 1.021277 (-5800 6000);
DISPLAY INVISIBLE (-5800 6000);
FORCEPROP 0 LASTPIN (-5950 5500) $PN BW53
J 2
(-5960 5510);
DISPLAY 0.489362 (-5960 5510);
PAINT MONO (-5960 5510);
FORCEPROP 0 LASTPIN (-5950 5400) $PN CA53
J 2
(-5960 5410);
DISPLAY 0.489362 (-5960 5410);
PAINT MONO (-5960 5410);
FORCEPROP 0 LASTPIN (-5950 5300) $PN BU53
J 2
(-5960 5310);
DISPLAY 0.489362 (-5960 5310);
PAINT MONO (-5960 5310);
FORCEPROP 0 LASTPIN (-5950 5200) $PN BW50
J 2
(-5960 5210);
DISPLAY 0.489362 (-5960 5210);
PAINT MONO (-5960 5210);
FORCEPROP 0 LASTPIN (-5950 5100) $PN CA50
J 2
(-5960 5110);
DISPLAY 0.489362 (-5960 5110);
PAINT MONO (-5960 5110);
FORCEPROP 0 LASTPIN (-5950 5000) $PN BU50
J 2
(-5960 5010);
DISPLAY 0.489362 (-5960 5010);
PAINT MONO (-5960 5010);
FORCEPROP 0 LASTPIN (-5950 4900) $PN BW47
J 2
(-5960 4910);
DISPLAY 0.489362 (-5960 4910);
PAINT MONO (-5960 4910);
FORCEPROP 0 LASTPIN (-5950 4800) $PN CA47
J 2
(-5960 4810);
DISPLAY 0.489362 (-5960 4810);
PAINT MONO (-5960 4810);
FORCEPROP 0 LASTPIN (-5950 4700) $PN BU47
J 2
(-5960 4710);
DISPLAY 0.489362 (-5960 4710);
PAINT MONO (-5960 4710);
FORCEPROP 0 LASTPIN (-5950 4600) $PN BW44
J 2
(-5960 4610);
DISPLAY 0.489362 (-5960 4610);
PAINT MONO (-5960 4610);
FORCEPROP 0 LASTPIN (-5950 4500) $PN CA44
J 2
(-5960 4510);
DISPLAY 0.489362 (-5960 4510);
PAINT MONO (-5960 4510);
FORCEPROP 0 LASTPIN (-5950 4400) $PN BU44
J 2
(-5960 4410);
DISPLAY 0.489362 (-5960 4410);
PAINT MONO (-5960 4410);
FORCEPROP 0 LASTPIN (-5950 4300) $PN BY41
J 2
(-5960 4310);
DISPLAY 0.489362 (-5960 4310);
PAINT MONO (-5960 4310);
FORCEPROP 0 LASTPIN (-5950 4200) $PN CB41
J 2
(-5960 4210);
DISPLAY 0.489362 (-5960 4210);
PAINT MONO (-5960 4210);
FORCEPROP 0 LASTPIN (-5950 4100) $PN BV41
J 2
(-5960 4110);
DISPLAY 0.489362 (-5960 4110);
PAINT MONO (-5960 4110);
FORCEPROP 0 LASTPIN (-5950 4000) $PN BT41
J 2
(-5960 4010);
DISPLAY 0.489362 (-5960 4010);
PAINT MONO (-5960 4010);
FORCEPROP 0 LASTPIN (-5950 5550) $PN BW52
J 2
(-5960 5560);
DISPLAY 0.489362 (-5960 5560);
PAINT MONO (-5960 5560);
FORCEPROP 0 LASTPIN (-5950 5450) $PN CA52
J 2
(-5960 5460);
DISPLAY 0.489362 (-5960 5460);
PAINT MONO (-5960 5460);
FORCEPROP 0 LASTPIN (-5950 5350) $PN BU52
J 2
(-5960 5360);
DISPLAY 0.489362 (-5960 5360);
PAINT MONO (-5960 5360);
FORCEPROP 0 LASTPIN (-5950 5250) $PN BW49
J 2
(-5960 5260);
DISPLAY 0.489362 (-5960 5260);
PAINT MONO (-5960 5260);
FORCEPROP 0 LASTPIN (-5950 5150) $PN CA49
J 2
(-5960 5160);
DISPLAY 0.489362 (-5960 5160);
PAINT MONO (-5960 5160);
FORCEPROP 0 LASTPIN (-5950 5050) $PN BU49
J 2
(-5960 5060);
DISPLAY 0.489362 (-5960 5060);
PAINT MONO (-5960 5060);
FORCEPROP 0 LASTPIN (-5950 4950) $PN BW46
J 2
(-5960 4960);
DISPLAY 0.489362 (-5960 4960);
PAINT MONO (-5960 4960);
FORCEPROP 0 LASTPIN (-5950 4850) $PN CA46
J 2
(-5960 4860);
DISPLAY 0.489362 (-5960 4860);
PAINT MONO (-5960 4860);
FORCEPROP 0 LASTPIN (-5950 4750) $PN BU46
J 2
(-5960 4760);
DISPLAY 0.489362 (-5960 4760);
PAINT MONO (-5960 4760);
FORCEPROP 0 LASTPIN (-5950 4650) $PN BW43
J 2
(-5960 4660);
DISPLAY 0.489362 (-5960 4660);
PAINT MONO (-5960 4660);
FORCEPROP 0 LASTPIN (-5950 4550) $PN CA43
J 2
(-5960 4560);
DISPLAY 0.489362 (-5960 4560);
PAINT MONO (-5960 4560);
FORCEPROP 0 LASTPIN (-5950 4450) $PN BU43
J 2
(-5960 4460);
DISPLAY 0.489362 (-5960 4460);
PAINT MONO (-5960 4460);
FORCEPROP 0 LASTPIN (-5950 4350) $PN BY40
J 2
(-5960 4360);
DISPLAY 0.489362 (-5960 4360);
PAINT MONO (-5960 4360);
FORCEPROP 0 LASTPIN (-5950 4250) $PN CB40
J 2
(-5960 4260);
DISPLAY 0.489362 (-5960 4260);
PAINT MONO (-5960 4260);
FORCEPROP 0 LASTPIN (-5950 4150) $PN BV40
J 2
(-5960 4160);
DISPLAY 0.489362 (-5960 4160);
PAINT MONO (-5960 4160);
FORCEPROP 0 LASTPIN (-5950 4050) $PN BT40
J 2
(-5960 4060);
DISPLAY 0.489362 (-5960 4060);
PAINT MONO (-5960 4060);
FORCEPROP 0 LASTPIN (-3450 5500) $PN CN52
J 0
(-3440 5510);
DISPLAY 0.489362 (-3440 5510);
PAINT MONO (-3440 5510);
FORCEPROP 0 LASTPIN (-3450 5400) $PN CR52
J 0
(-3440 5410);
DISPLAY 0.489362 (-3440 5410);
PAINT MONO (-3440 5410);
FORCEPROP 0 LASTPIN (-3450 5300) $PN CL52
J 0
(-3440 5310);
DISPLAY 0.489362 (-3440 5310);
PAINT MONO (-3440 5310);
FORCEPROP 0 LASTPIN (-3450 5200) $PN CN49
J 0
(-3440 5210);
DISPLAY 0.489362 (-3440 5210);
PAINT MONO (-3440 5210);
FORCEPROP 0 LASTPIN (-3450 5100) $PN CR49
J 0
(-3440 5110);
DISPLAY 0.489362 (-3440 5110);
PAINT MONO (-3440 5110);
FORCEPROP 0 LASTPIN (-3450 5000) $PN CU49
J 0
(-3440 5010);
DISPLAY 0.489362 (-3440 5010);
PAINT MONO (-3440 5010);
FORCEPROP 0 LASTPIN (-3450 4900) $PN CL49
J 0
(-3440 4910);
DISPLAY 0.489362 (-3440 4910);
PAINT MONO (-3440 4910);
FORCEPROP 0 LASTPIN (-3450 4800) $PN CR46
J 0
(-3440 4810);
DISPLAY 0.489362 (-3440 4810);
PAINT MONO (-3440 4810);
FORCEPROP 0 LASTPIN (-3450 4700) $PN CU46
J 0
(-3440 4710);
DISPLAY 0.489362 (-3440 4710);
PAINT MONO (-3440 4710);
FORCEPROP 0 LASTPIN (-3450 4600) $PN CN46
J 0
(-3440 4610);
DISPLAY 0.489362 (-3440 4610);
PAINT MONO (-3440 4610);
FORCEPROP 0 LASTPIN (-3450 4500) $PN CR43
J 0
(-3440 4510);
DISPLAY 0.489362 (-3440 4510);
PAINT MONO (-3440 4510);
FORCEPROP 0 LASTPIN (-3450 4400) $PN CU43
J 0
(-3440 4410);
DISPLAY 0.489362 (-3440 4410);
PAINT MONO (-3440 4410);
FORCEPROP 0 LASTPIN (-3450 4300) $PN CN43
J 0
(-3440 4310);
DISPLAY 0.489362 (-3440 4310);
PAINT MONO (-3440 4310);
FORCEPROP 0 LASTPIN (-3450 4200) $PN CT40
J 0
(-3440 4210);
DISPLAY 0.489362 (-3440 4210);
PAINT MONO (-3440 4210);
FORCEPROP 0 LASTPIN (-3450 4100) $PN CP40
J 0
(-3440 4110);
DISPLAY 0.489362 (-3440 4110);
PAINT MONO (-3440 4110);
FORCEPROP 0 LASTPIN (-3450 4000) $PN CM40
J 0
(-3440 4010);
DISPLAY 0.489362 (-3440 4010);
PAINT MONO (-3440 4010);
FORCEPROP 0 LASTPIN (-3450 5550) $PN CN53
J 0
(-3440 5560);
DISPLAY 0.489362 (-3440 5560);
PAINT MONO (-3440 5560);
FORCEPROP 0 LASTPIN (-3450 5450) $PN CR53
J 0
(-3440 5460);
DISPLAY 0.489362 (-3440 5460);
PAINT MONO (-3440 5460);
FORCEPROP 0 LASTPIN (-3450 5350) $PN CL53
J 0
(-3440 5360);
DISPLAY 0.489362 (-3440 5360);
PAINT MONO (-3440 5360);
FORCEPROP 0 LASTPIN (-3450 5250) $PN CN50
J 0
(-3440 5260);
DISPLAY 0.489362 (-3440 5260);
PAINT MONO (-3440 5260);
FORCEPROP 0 LASTPIN (-3450 5150) $PN CR50
J 0
(-3440 5160);
DISPLAY 0.489362 (-3440 5160);
PAINT MONO (-3440 5160);
FORCEPROP 0 LASTPIN (-3450 5050) $PN CU50
J 0
(-3440 5060);
DISPLAY 0.489362 (-3440 5060);
PAINT MONO (-3440 5060);
FORCEPROP 0 LASTPIN (-3450 4950) $PN CL50
J 0
(-3440 4960);
DISPLAY 0.489362 (-3440 4960);
PAINT MONO (-3440 4960);
FORCEPROP 0 LASTPIN (-3450 4850) $PN CR47
J 0
(-3440 4860);
DISPLAY 0.489362 (-3440 4860);
PAINT MONO (-3440 4860);
FORCEPROP 0 LASTPIN (-3450 4750) $PN CU47
J 0
(-3440 4760);
DISPLAY 0.489362 (-3440 4760);
PAINT MONO (-3440 4760);
FORCEPROP 0 LASTPIN (-3450 4650) $PN CN47
J 0
(-3440 4660);
DISPLAY 0.489362 (-3440 4660);
PAINT MONO (-3440 4660);
FORCEPROP 0 LASTPIN (-3450 4550) $PN CR44
J 0
(-3440 4560);
DISPLAY 0.489362 (-3440 4560);
PAINT MONO (-3440 4560);
FORCEPROP 0 LASTPIN (-3450 4450) $PN CU44
J 0
(-3440 4460);
DISPLAY 0.489362 (-3440 4460);
PAINT MONO (-3440 4460);
FORCEPROP 0 LASTPIN (-3450 4350) $PN CN44
J 0
(-3440 4360);
DISPLAY 0.489362 (-3440 4360);
PAINT MONO (-3440 4360);
FORCEPROP 0 LASTPIN (-3450 4250) $PN CT41
J 0
(-3440 4260);
DISPLAY 0.489362 (-3440 4260);
PAINT MONO (-3440 4260);
FORCEPROP 0 LASTPIN (-3450 4150) $PN CP41
J 0
(-3440 4160);
DISPLAY 0.489362 (-3440 4160);
PAINT MONO (-3440 4160);
FORCEPROP 0 LASTPIN (-3450 4050) $PN CM41
J 0
(-3440 4060);
DISPLAY 0.489362 (-3440 4060);
PAINT MONO (-3440 4060);
FORCEPROP 1 LAST MATERIAL IO
J 0
(-5795 5732);
DISPLAY 0.489362 (-5795 5732);
PAINT SKYBLUE (-5795 5732);
FORCEPROP 2 LAST VALUE SOCKET6096_13568-001
J 0
(-5800 5828);
DISPLAY 0.489362 (-5800 5828);
PAINT SKYBLUE (-5800 5828);
FORCEPROP 2 LAST PART_TYPE SMLF
J 0
(-5800 5928);
DISPLAY 1.021277 (-5800 5928);
FORCEPROP 1 LAST CDS_LMAN_SYM_OUTLINE -1100,950,1100,-950
J 0
(-4700 4750);
DISPLAY 0.468085 (-4700 4750);
PAINT GREEN (-4700 4750);
DISPLAY INVISIBLE (-4700 4750);
FORCEPROP 1 LAST NEEDS_NO_SIZE TRUE
J 0
(-4700 4750);
DISPLAY 0.723404 (-4700 4750);
PAINT GREEN (-4700 4750);
DISPLAY INVISIBLE (-4700 4750);
FORCEPROP 2 LAST CDS_LIB pure_quanta
J 0
(-4700 4750);
DISPLAY INVISIBLE (-4700 4750);
FORCEPROP 1 LAST PATH I147
J 0
(-4700 4750);
DISPLAY 0.723404 (-4700 4750);
PAINT GREEN (-4700 4750);
DISPLAY INVISIBLE (-4700 4750);
FORCEPROP 1 LAST PART_NUMBER DGA^6000030
J 0
(-5795 5859);
DISPLAY 0.489362 (-5795 5859);
PAINT SKYBLUE (-5795 5859);
DISPLAY INVISIBLE (-5795 5859);
FORCEADD GENOA_SP5..16
(-4700 2100);
FORCEPROP 1 LAST LOCATION U26
J 0
(-5800 3225);
DISPLAY 0.489362 (-5800 3225);
PAINT SKYBLUE (-5800 3225);
FORCEPROP 0 LAST $SEC 16
J 0
(-5775 3400);
DISPLAY 0.680851 (-5775 3400);
PAINT MONO (-5775 3400);
DISPLAY INVISIBLE (-5775 3400);
FORCEPROP 0 LAST CDS_SEC 16
J 0
(-5800 3250);
DISPLAY 1.021277 (-5800 3250);
DISPLAY INVISIBLE (-5800 3250);
FORCEPROP 0 LASTPIN (-5950 2850) $PN CE53
J 2
(-5960 2860);
DISPLAY 0.489362 (-5960 2860);
PAINT MONO (-5960 2860);
FORCEPROP 0 LASTPIN (-5950 2750) $PN CG53
J 2
(-5960 2760);
DISPLAY 0.489362 (-5960 2760);
PAINT MONO (-5960 2760);
FORCEPROP 0 LASTPIN (-5950 2650) $PN CC53
J 2
(-5960 2660);
DISPLAY 0.489362 (-5960 2660);
PAINT MONO (-5960 2660);
FORCEPROP 0 LASTPIN (-5950 2550) $PN CE50
J 2
(-5960 2560);
DISPLAY 0.489362 (-5960 2560);
PAINT MONO (-5960 2560);
FORCEPROP 0 LASTPIN (-5950 2450) $PN CG50
J 2
(-5960 2460);
DISPLAY 0.489362 (-5960 2460);
PAINT MONO (-5960 2460);
FORCEPROP 0 LASTPIN (-5950 2350) $PN CC50
J 2
(-5960 2360);
DISPLAY 0.489362 (-5960 2360);
PAINT MONO (-5960 2360);
FORCEPROP 0 LASTPIN (-5950 2250) $PN CE47
J 2
(-5960 2260);
DISPLAY 0.489362 (-5960 2260);
PAINT MONO (-5960 2260);
FORCEPROP 0 LASTPIN (-5950 2150) $PN CG47
J 2
(-5960 2160);
DISPLAY 0.489362 (-5960 2160);
PAINT MONO (-5960 2160);
FORCEPROP 0 LASTPIN (-5950 2050) $PN CC47
J 2
(-5960 2060);
DISPLAY 0.489362 (-5960 2060);
PAINT MONO (-5960 2060);
FORCEPROP 0 LASTPIN (-5950 1950) $PN CE44
J 2
(-5960 1960);
DISPLAY 0.489362 (-5960 1960);
PAINT MONO (-5960 1960);
FORCEPROP 0 LASTPIN (-5950 1850) $PN CG44
J 2
(-5960 1860);
DISPLAY 0.489362 (-5960 1860);
PAINT MONO (-5960 1860);
FORCEPROP 0 LASTPIN (-5950 1750) $PN CJ44
J 2
(-5960 1760);
DISPLAY 0.489362 (-5960 1760);
PAINT MONO (-5960 1760);
FORCEPROP 0 LASTPIN (-5950 1650) $PN CC44
J 2
(-5960 1660);
DISPLAY 0.489362 (-5960 1660);
PAINT MONO (-5960 1660);
FORCEPROP 0 LASTPIN (-5950 1550) $PN CH41
J 2
(-5960 1560);
DISPLAY 0.489362 (-5960 1560);
PAINT MONO (-5960 1560);
FORCEPROP 0 LASTPIN (-5950 1450) $PN CF41
J 2
(-5960 1460);
DISPLAY 0.489362 (-5960 1460);
PAINT MONO (-5960 1460);
FORCEPROP 0 LASTPIN (-5950 1350) $PN CD41
J 2
(-5960 1360);
DISPLAY 0.489362 (-5960 1360);
PAINT MONO (-5960 1360);
FORCEPROP 0 LASTPIN (-5950 2900) $PN CE52
J 2
(-5960 2910);
DISPLAY 0.489362 (-5960 2910);
PAINT MONO (-5960 2910);
FORCEPROP 0 LASTPIN (-5950 2800) $PN CG52
J 2
(-5960 2810);
DISPLAY 0.489362 (-5960 2810);
PAINT MONO (-5960 2810);
FORCEPROP 0 LASTPIN (-5950 2700) $PN CC52
J 2
(-5960 2710);
DISPLAY 0.489362 (-5960 2710);
PAINT MONO (-5960 2710);
FORCEPROP 0 LASTPIN (-5950 2600) $PN CE49
J 2
(-5960 2610);
DISPLAY 0.489362 (-5960 2610);
PAINT MONO (-5960 2610);
FORCEPROP 0 LASTPIN (-5950 2500) $PN CG49
J 2
(-5960 2510);
DISPLAY 0.489362 (-5960 2510);
PAINT MONO (-5960 2510);
FORCEPROP 0 LASTPIN (-5950 2400) $PN CC49
J 2
(-5960 2410);
DISPLAY 0.489362 (-5960 2410);
PAINT MONO (-5960 2410);
FORCEPROP 0 LASTPIN (-5950 2300) $PN CE46
J 2
(-5960 2310);
DISPLAY 0.489362 (-5960 2310);
PAINT MONO (-5960 2310);
FORCEPROP 0 LASTPIN (-5950 2200) $PN CG46
J 2
(-5960 2210);
DISPLAY 0.489362 (-5960 2210);
PAINT MONO (-5960 2210);
FORCEPROP 0 LASTPIN (-5950 2100) $PN CC46
J 2
(-5960 2110);
DISPLAY 0.489362 (-5960 2110);
PAINT MONO (-5960 2110);
FORCEPROP 0 LASTPIN (-5950 2000) $PN CE43
J 2
(-5960 2010);
DISPLAY 0.489362 (-5960 2010);
PAINT MONO (-5960 2010);
FORCEPROP 0 LASTPIN (-5950 1900) $PN CG43
J 2
(-5960 1910);
DISPLAY 0.489362 (-5960 1910);
PAINT MONO (-5960 1910);
FORCEPROP 0 LASTPIN (-5950 1800) $PN CJ43
J 2
(-5960 1810);
DISPLAY 0.489362 (-5960 1810);
PAINT MONO (-5960 1810);
FORCEPROP 0 LASTPIN (-5950 1700) $PN CC43
J 2
(-5960 1710);
DISPLAY 0.489362 (-5960 1710);
PAINT MONO (-5960 1710);
FORCEPROP 0 LASTPIN (-5950 1600) $PN CH40
J 2
(-5960 1610);
DISPLAY 0.489362 (-5960 1610);
PAINT MONO (-5960 1610);
FORCEPROP 0 LASTPIN (-5950 1500) $PN CF40
J 2
(-5960 1510);
DISPLAY 0.489362 (-5960 1510);
PAINT MONO (-5960 1510);
FORCEPROP 0 LASTPIN (-5950 1400) $PN CD40
J 2
(-5960 1410);
DISPLAY 0.489362 (-5960 1410);
PAINT MONO (-5960 1410);
FORCEPROP 0 LASTPIN (-3450 2850) $PN CU52
J 0
(-3440 2860);
DISPLAY 0.489362 (-3440 2860);
PAINT MONO (-3440 2860);
FORCEPROP 0 LASTPIN (-3450 2750) $PN DA52
J 0
(-3440 2760);
DISPLAY 0.489362 (-3440 2760);
PAINT MONO (-3440 2760);
FORCEPROP 0 LASTPIN (-3450 2650) $PN DC52
J 0
(-3440 2660);
DISPLAY 0.489362 (-3440 2660);
PAINT MONO (-3440 2660);
FORCEPROP 0 LASTPIN (-3450 2550) $PN CW52
J 0
(-3440 2560);
DISPLAY 0.489362 (-3440 2560);
PAINT MONO (-3440 2560);
FORCEPROP 0 LASTPIN (-3450 2450) $PN DA49
J 0
(-3440 2460);
DISPLAY 0.489362 (-3440 2460);
PAINT MONO (-3440 2460);
FORCEPROP 0 LASTPIN (-3450 2350) $PN DC49
J 0
(-3440 2360);
DISPLAY 0.489362 (-3440 2360);
PAINT MONO (-3440 2360);
FORCEPROP 0 LASTPIN (-3450 2250) $PN CW49
J 0
(-3440 2260);
DISPLAY 0.489362 (-3440 2260);
PAINT MONO (-3440 2260);
FORCEPROP 0 LASTPIN (-3450 2150) $PN DA46
J 0
(-3440 2160);
DISPLAY 0.489362 (-3440 2160);
PAINT MONO (-3440 2160);
FORCEPROP 0 LASTPIN (-3450 2050) $PN DC46
J 0
(-3440 2060);
DISPLAY 0.489362 (-3440 2060);
PAINT MONO (-3440 2060);
FORCEPROP 0 LASTPIN (-3450 1950) $PN CW46
J 0
(-3440 1960);
DISPLAY 0.489362 (-3440 1960);
PAINT MONO (-3440 1960);
FORCEPROP 0 LASTPIN (-3450 1850) $PN DA43
J 0
(-3440 1860);
DISPLAY 0.489362 (-3440 1860);
PAINT MONO (-3440 1860);
FORCEPROP 0 LASTPIN (-3450 1750) $PN DC43
J 0
(-3440 1760);
DISPLAY 0.489362 (-3440 1760);
PAINT MONO (-3440 1760);
FORCEPROP 0 LASTPIN (-3450 1650) $PN CW43
J 0
(-3440 1660);
DISPLAY 0.489362 (-3440 1660);
PAINT MONO (-3440 1660);
FORCEPROP 0 LASTPIN (-3450 1550) $PN DB40
J 0
(-3440 1560);
DISPLAY 0.489362 (-3440 1560);
PAINT MONO (-3440 1560);
FORCEPROP 0 LASTPIN (-3450 1450) $PN CY40
J 0
(-3440 1460);
DISPLAY 0.489362 (-3440 1460);
PAINT MONO (-3440 1460);
FORCEPROP 0 LASTPIN (-3450 1350) $PN CV40
J 0
(-3440 1360);
DISPLAY 0.489362 (-3440 1360);
PAINT MONO (-3440 1360);
FORCEPROP 0 LASTPIN (-3450 2900) $PN CU53
J 0
(-3440 2910);
DISPLAY 0.489362 (-3440 2910);
PAINT MONO (-3440 2910);
FORCEPROP 0 LASTPIN (-3450 2800) $PN DA53
J 0
(-3440 2810);
DISPLAY 0.489362 (-3440 2810);
PAINT MONO (-3440 2810);
FORCEPROP 0 LASTPIN (-3450 2700) $PN DC53
J 0
(-3440 2710);
DISPLAY 0.489362 (-3440 2710);
PAINT MONO (-3440 2710);
FORCEPROP 0 LASTPIN (-3450 2600) $PN CW53
J 0
(-3440 2610);
DISPLAY 0.489362 (-3440 2610);
PAINT MONO (-3440 2610);
FORCEPROP 0 LASTPIN (-3450 2500) $PN DA50
J 0
(-3440 2510);
DISPLAY 0.489362 (-3440 2510);
PAINT MONO (-3440 2510);
FORCEPROP 0 LASTPIN (-3450 2400) $PN DC50
J 0
(-3440 2410);
DISPLAY 0.489362 (-3440 2410);
PAINT MONO (-3440 2410);
FORCEPROP 0 LASTPIN (-3450 2300) $PN CW50
J 0
(-3440 2310);
DISPLAY 0.489362 (-3440 2310);
PAINT MONO (-3440 2310);
FORCEPROP 0 LASTPIN (-3450 2200) $PN DA47
J 0
(-3440 2210);
DISPLAY 0.489362 (-3440 2210);
PAINT MONO (-3440 2210);
FORCEPROP 0 LASTPIN (-3450 2100) $PN DC47
J 0
(-3440 2110);
DISPLAY 0.489362 (-3440 2110);
PAINT MONO (-3440 2110);
FORCEPROP 0 LASTPIN (-3450 2000) $PN CW47
J 0
(-3440 2010);
DISPLAY 0.489362 (-3440 2010);
PAINT MONO (-3440 2010);
FORCEPROP 0 LASTPIN (-3450 1900) $PN DA44
J 0
(-3440 1910);
DISPLAY 0.489362 (-3440 1910);
PAINT MONO (-3440 1910);
FORCEPROP 0 LASTPIN (-3450 1800) $PN DC44
J 0
(-3440 1810);
DISPLAY 0.489362 (-3440 1810);
PAINT MONO (-3440 1810);
FORCEPROP 0 LASTPIN (-3450 1700) $PN CW44
J 0
(-3440 1710);
DISPLAY 0.489362 (-3440 1710);
PAINT MONO (-3440 1710);
FORCEPROP 0 LASTPIN (-3450 1600) $PN DB41
J 0
(-3440 1610);
DISPLAY 0.489362 (-3440 1610);
PAINT MONO (-3440 1610);
FORCEPROP 0 LASTPIN (-3450 1500) $PN CY41
J 0
(-3440 1510);
DISPLAY 0.489362 (-3440 1510);
PAINT MONO (-3440 1510);
FORCEPROP 0 LASTPIN (-3450 1400) $PN CV41
J 0
(-3440 1410);
DISPLAY 0.489362 (-3440 1410);
PAINT MONO (-3440 1410);
FORCEPROP 2 LAST PART_TYPE SMLF
J 0
(-5800 3175);
DISPLAY 1.021277 (-5800 3175);
FORCEPROP 1 LAST MATERIAL IO
J 0
(-5800 3075);
DISPLAY 0.489362 (-5800 3075);
PAINT SKYBLUE (-5800 3075);
FORCEPROP 2 LAST VALUE SOCKET6096_13568-001
J 0
(-5800 3125);
DISPLAY 0.489362 (-5800 3125);
PAINT SKYBLUE (-5800 3125);
FORCEPROP 2 LAST CDS_LIB pure_quanta
J 0
(-4700 2100);
DISPLAY INVISIBLE (-4700 2100);
FORCEPROP 1 LAST CDS_LMAN_SYM_OUTLINE -1100,950,1100,-950
J 0
(-4700 2100);
DISPLAY 0.468085 (-4700 2100);
PAINT GREEN (-4700 2100);
DISPLAY INVISIBLE (-4700 2100);
FORCEPROP 1 LAST NEEDS_NO_SIZE TRUE
J 0
(-4700 2100);
DISPLAY 0.723404 (-4700 2100);
PAINT GREEN (-4700 2100);
DISPLAY INVISIBLE (-4700 2100);
FORCEPROP 1 LAST PATH I148
J 0
(-4700 2100);
DISPLAY 0.723404 (-4700 2100);
PAINT GREEN (-4700 2100);
DISPLAY INVISIBLE (-4700 2100);
FORCEPROP 1 LAST PART_NUMBER DGA^6000030
J 0
(-5800 3150);
DISPLAY 0.489362 (-5800 3150);
PAINT SKYBLUE (-5800 3150);
DISPLAY INVISIBLE (-5800 3150);
FORCEADD OFFPAGE..2
(-1900 3075);
FORCEPROP 2 LAST $XR0 66 
J 0
(-1711 3075);
DISPLAY 0.638298 (-1711 3075);
PAINT MONO (-1711 3075);
FORCEPROP 2 LAST CDS_LIB standard
J 0
(-1900 3075);
DISPLAY INVISIBLE (-1900 3075);
FORCEPROP 1 LAST OFFPAGE TRUE
J 0
(-1575 2950);
DISPLAY 0.872340 (-1575 2950);
PAINT GREEN (-1575 2950);
DISPLAY INVISIBLE (-1575 2950);
FORCEPROP 1 LAST COMMENT_BODY TRUE
J 0
(-1945 2980);
DISPLAY 0.872340 (-1945 2980);
PAINT GREEN (-1945 2980);
DISPLAY INVISIBLE (-1945 2980);
FORCEPROP 2 LAST PATH I183
J 0
(-1700 3125);
DISPLAY 1.021277 (-1700 3125);
DISPLAY INVISIBLE (-1700 3125);
FORCEADD OFFPAGE..2
(-1900 3125);
FORCEPROP 2 LAST $XR0 66 
J 0
(-1711 3125);
DISPLAY 0.638298 (-1711 3125);
PAINT MONO (-1711 3125);
FORCEPROP 2 LAST CDS_LIB standard
J 0
(-1900 3125);
DISPLAY INVISIBLE (-1900 3125);
FORCEPROP 1 LAST OFFPAGE TRUE
J 0
(-1575 3000);
DISPLAY 0.872340 (-1575 3000);
PAINT GREEN (-1575 3000);
DISPLAY INVISIBLE (-1575 3000);
FORCEPROP 1 LAST COMMENT_BODY TRUE
J 0
(-1945 3030);
DISPLAY 0.872340 (-1945 3030);
PAINT GREEN (-1945 3030);
DISPLAY INVISIBLE (-1945 3030);
FORCEPROP 2 LAST PATH I184
J 0
(-1700 3175);
DISPLAY 1.021277 (-1700 3175);
DISPLAY INVISIBLE (-1700 3175);
FORCEADD TAP..6
R 2
(-2875 2850);
FORCEPROP 3 LASTPIN (-2925 2850) SIG_NAME P5E_CPU1_P1_TX_DN<0>
J 0
(-2915 2860);
DISPLAY 0.659574 (-2915 2860);
PAINT MONO (-2915 2860);
DISPLAY INVISIBLE (-2915 2860);
FORCEPROP 1 LASTPIN (-2925 2850) BN 0
J 2
(-2873 2858);
DISPLAY 0.489362 (-2873 2858);
PAINT MONO (-2873 2858);
FORCEPROP 2 LAST ROOM RISER1
J 0
(-3375 2900);
DISPLAY 0.829787 (-3375 2900);
PAINT RED (-3375 2900);
DISPLAY INVISIBLE (-3375 2900);
FORCEPROP 2 LAST BOM_COST IO_SLOT
J 0
(-3375 2950);
DISPLAY 0.829787 (-3375 2950);
DISPLAY INVISIBLE (-3375 2950);
FORCEPROP 2 LAST CDS_LIB mstr_standard
J 0
(-2875 2850);
DISPLAY INVISIBLE (-2875 2850);
FORCEPROP 1 LAST BODY_TYPE PLUMBING
J 2
(-2875 2800);
DISPLAY 0.702128 (-2875 2800);
PAINT GREEN (-2875 2800);
DISPLAY INVISIBLE (-2875 2800);
FORCEPROP 1 LAST HDL_TAP TRUE
J 2
(-3200 2725);
DISPLAY 0.702128 (-3200 2725);
PAINT GREEN (-3200 2725);
DISPLAY INVISIBLE (-3200 2725);
FORCEPROP 1 LAST PATH I186
J 2
(-2873 2850);
DISPLAY 0.872340 (-2873 2850);
PAINT GREEN (-2873 2850);
DISPLAY INVISIBLE (-2873 2850);
FORCEADD TAP..6
R 2
(-2875 2750);
FORCEPROP 3 LASTPIN (-2925 2750) SIG_NAME P5E_CPU1_P1_TX_DN<1>
J 0
(-2915 2760);
DISPLAY 0.659574 (-2915 2760);
PAINT MONO (-2915 2760);
DISPLAY INVISIBLE (-2915 2760);
FORCEPROP 1 LASTPIN (-2925 2750) BN 1
J 2
(-2873 2758);
DISPLAY 0.489362 (-2873 2758);
PAINT MONO (-2873 2758);
FORCEPROP 2 LAST ROOM RISER1
J 0
(-3375 2800);
DISPLAY 0.829787 (-3375 2800);
PAINT RED (-3375 2800);
DISPLAY INVISIBLE (-3375 2800);
FORCEPROP 2 LAST CDS_LIB mstr_standard
J 0
(-2875 2750);
DISPLAY INVISIBLE (-2875 2750);
FORCEPROP 2 LAST BOM_COST IO_SLOT
J 0
(-3375 2850);
DISPLAY 0.829787 (-3375 2850);
DISPLAY INVISIBLE (-3375 2850);
FORCEPROP 1 LAST BODY_TYPE PLUMBING
J 2
(-2875 2700);
DISPLAY 0.702128 (-2875 2700);
PAINT GREEN (-2875 2700);
DISPLAY INVISIBLE (-2875 2700);
FORCEPROP 1 LAST HDL_TAP TRUE
J 2
(-3200 2625);
DISPLAY 0.702128 (-3200 2625);
PAINT GREEN (-3200 2625);
DISPLAY INVISIBLE (-3200 2625);
FORCEPROP 1 LAST PATH I187
J 2
(-2873 2750);
DISPLAY 0.872340 (-2873 2750);
PAINT GREEN (-2873 2750);
DISPLAY INVISIBLE (-2873 2750);
FORCEADD TAP..6
R 2
(-2875 2650);
FORCEPROP 3 LASTPIN (-2925 2650) SIG_NAME P5E_CPU1_P1_TX_DN<2>
J 0
(-2915 2660);
DISPLAY 0.659574 (-2915 2660);
PAINT MONO (-2915 2660);
DISPLAY INVISIBLE (-2915 2660);
FORCEPROP 1 LASTPIN (-2925 2650) BN 2
J 2
(-2873 2658);
DISPLAY 0.489362 (-2873 2658);
PAINT MONO (-2873 2658);
FORCEPROP 2 LAST ROOM RISER1
J 0
(-3375 2700);
DISPLAY 0.829787 (-3375 2700);
PAINT RED (-3375 2700);
DISPLAY INVISIBLE (-3375 2700);
FORCEPROP 2 LAST CDS_LIB standard
J 0
(-2875 2650);
DISPLAY INVISIBLE (-2875 2650);
FORCEPROP 2 LAST BOM_COST IO_SLOT
J 0
(-3375 2750);
DISPLAY 0.829787 (-3375 2750);
DISPLAY INVISIBLE (-3375 2750);
FORCEPROP 1 LAST BODY_TYPE PLUMBING
J 2
(-2875 2600);
DISPLAY 0.702128 (-2875 2600);
PAINT GREEN (-2875 2600);
DISPLAY INVISIBLE (-2875 2600);
FORCEPROP 1 LAST HDL_TAP TRUE
J 2
(-3200 2525);
DISPLAY 0.702128 (-3200 2525);
PAINT GREEN (-3200 2525);
DISPLAY INVISIBLE (-3200 2525);
FORCEPROP 1 LAST PATH I188
J 2
(-2873 2650);
DISPLAY 0.872340 (-2873 2650);
PAINT GREEN (-2873 2650);
DISPLAY INVISIBLE (-2873 2650);
FORCEADD TAP..6
R 2
(-2875 2450);
FORCEPROP 3 LASTPIN (-2925 2450) SIG_NAME P5E_CPU1_P1_TX_DN<4>
J 0
(-2915 2460);
DISPLAY 0.659574 (-2915 2460);
PAINT MONO (-2915 2460);
DISPLAY INVISIBLE (-2915 2460);
FORCEPROP 1 LASTPIN (-2925 2450) BN 4
J 2
(-2873 2458);
DISPLAY 0.489362 (-2873 2458);
PAINT MONO (-2873 2458);
FORCEPROP 2 LAST ROOM RISER1
J 0
(-3375 2500);
DISPLAY 0.829787 (-3375 2500);
PAINT RED (-3375 2500);
DISPLAY INVISIBLE (-3375 2500);
FORCEPROP 2 LAST CDS_LIB standard
J 0
(-2875 2450);
DISPLAY INVISIBLE (-2875 2450);
FORCEPROP 2 LAST BOM_COST IO_SLOT
J 0
(-3375 2550);
DISPLAY 0.829787 (-3375 2550);
DISPLAY INVISIBLE (-3375 2550);
FORCEPROP 1 LAST BODY_TYPE PLUMBING
J 2
(-2875 2400);
DISPLAY 0.702128 (-2875 2400);
PAINT GREEN (-2875 2400);
DISPLAY INVISIBLE (-2875 2400);
FORCEPROP 1 LAST HDL_TAP TRUE
J 2
(-3200 2325);
DISPLAY 0.702128 (-3200 2325);
PAINT GREEN (-3200 2325);
DISPLAY INVISIBLE (-3200 2325);
FORCEPROP 1 LAST PATH I189
J 2
(-2873 2450);
DISPLAY 0.872340 (-2873 2450);
PAINT GREEN (-2873 2450);
DISPLAY INVISIBLE (-2873 2450);
FORCEADD TAP..6
R 2
(-2875 2550);
FORCEPROP 3 LASTPIN (-2925 2550) SIG_NAME P5E_CPU1_P1_TX_DN<3>
J 0
(-2915 2560);
DISPLAY 0.659574 (-2915 2560);
PAINT MONO (-2915 2560);
DISPLAY INVISIBLE (-2915 2560);
FORCEPROP 1 LASTPIN (-2925 2550) BN 3
J 2
(-2873 2558);
DISPLAY 0.489362 (-2873 2558);
PAINT MONO (-2873 2558);
FORCEPROP 2 LAST ROOM RISER1
J 0
(-3375 2600);
DISPLAY 0.829787 (-3375 2600);
PAINT RED (-3375 2600);
DISPLAY INVISIBLE (-3375 2600);
FORCEPROP 2 LAST CDS_LIB standard
J 0
(-2875 2550);
DISPLAY INVISIBLE (-2875 2550);
FORCEPROP 2 LAST BOM_COST IO_SLOT
J 0
(-3375 2650);
DISPLAY 0.829787 (-3375 2650);
DISPLAY INVISIBLE (-3375 2650);
FORCEPROP 1 LAST BODY_TYPE PLUMBING
J 2
(-2875 2500);
DISPLAY 0.702128 (-2875 2500);
PAINT GREEN (-2875 2500);
DISPLAY INVISIBLE (-2875 2500);
FORCEPROP 1 LAST HDL_TAP TRUE
J 2
(-3200 2425);
DISPLAY 0.702128 (-3200 2425);
PAINT GREEN (-3200 2425);
DISPLAY INVISIBLE (-3200 2425);
FORCEPROP 1 LAST PATH I190
J 2
(-2873 2550);
DISPLAY 0.872340 (-2873 2550);
PAINT GREEN (-2873 2550);
DISPLAY INVISIBLE (-2873 2550);
FORCEADD TAP..6
R 2
(-2875 2350);
FORCEPROP 3 LASTPIN (-2925 2350) SIG_NAME P5E_CPU1_P1_TX_DN<5>
J 0
(-2915 2360);
DISPLAY 0.659574 (-2915 2360);
PAINT MONO (-2915 2360);
DISPLAY INVISIBLE (-2915 2360);
FORCEPROP 1 LASTPIN (-2925 2350) BN 5
J 2
(-2873 2358);
DISPLAY 0.489362 (-2873 2358);
PAINT MONO (-2873 2358);
FORCEPROP 2 LAST ROOM RISER1
J 0
(-3375 2400);
DISPLAY 0.829787 (-3375 2400);
PAINT RED (-3375 2400);
DISPLAY INVISIBLE (-3375 2400);
FORCEPROP 2 LAST CDS_LIB standard
J 0
(-2875 2350);
DISPLAY INVISIBLE (-2875 2350);
FORCEPROP 2 LAST BOM_COST IO_SLOT
J 0
(-3375 2450);
DISPLAY 0.829787 (-3375 2450);
DISPLAY INVISIBLE (-3375 2450);
FORCEPROP 1 LAST BODY_TYPE PLUMBING
J 2
(-2875 2300);
DISPLAY 0.702128 (-2875 2300);
PAINT GREEN (-2875 2300);
DISPLAY INVISIBLE (-2875 2300);
FORCEPROP 1 LAST HDL_TAP TRUE
J 2
(-3200 2225);
DISPLAY 0.702128 (-3200 2225);
PAINT GREEN (-3200 2225);
DISPLAY INVISIBLE (-3200 2225);
FORCEPROP 1 LAST PATH I191
J 2
(-2873 2350);
DISPLAY 0.872340 (-2873 2350);
PAINT GREEN (-2873 2350);
DISPLAY INVISIBLE (-2873 2350);
FORCEADD TAP..6
R 2
(-2875 2250);
FORCEPROP 3 LASTPIN (-2925 2250) SIG_NAME P5E_CPU1_P1_TX_DN<6>
J 0
(-2915 2260);
DISPLAY 0.659574 (-2915 2260);
PAINT MONO (-2915 2260);
DISPLAY INVISIBLE (-2915 2260);
FORCEPROP 1 LASTPIN (-2925 2250) BN 6
J 2
(-2873 2258);
DISPLAY 0.489362 (-2873 2258);
PAINT MONO (-2873 2258);
FORCEPROP 2 LAST ROOM RISER1
J 0
(-3375 2300);
DISPLAY 0.829787 (-3375 2300);
PAINT RED (-3375 2300);
DISPLAY INVISIBLE (-3375 2300);
FORCEPROP 2 LAST CDS_LIB standard
J 0
(-2875 2250);
DISPLAY INVISIBLE (-2875 2250);
FORCEPROP 2 LAST BOM_COST IO_SLOT
J 0
(-3375 2350);
DISPLAY 0.829787 (-3375 2350);
DISPLAY INVISIBLE (-3375 2350);
FORCEPROP 1 LAST BODY_TYPE PLUMBING
J 2
(-2875 2200);
DISPLAY 0.702128 (-2875 2200);
PAINT GREEN (-2875 2200);
DISPLAY INVISIBLE (-2875 2200);
FORCEPROP 1 LAST HDL_TAP TRUE
J 2
(-3200 2125);
DISPLAY 0.702128 (-3200 2125);
PAINT GREEN (-3200 2125);
DISPLAY INVISIBLE (-3200 2125);
FORCEPROP 1 LAST PATH I192
J 2
(-2873 2250);
DISPLAY 0.872340 (-2873 2250);
PAINT GREEN (-2873 2250);
DISPLAY INVISIBLE (-2873 2250);
FORCEADD TAP..6
R 2
(-2875 2050);
FORCEPROP 3 LASTPIN (-2925 2050) SIG_NAME P5E_CPU1_P1_TX_DN<8>
J 0
(-2915 2060);
DISPLAY 0.659574 (-2915 2060);
PAINT MONO (-2915 2060);
DISPLAY INVISIBLE (-2915 2060);
FORCEPROP 1 LASTPIN (-2925 2050) BN 8
J 2
(-2873 2058);
DISPLAY 0.489362 (-2873 2058);
PAINT MONO (-2873 2058);
FORCEPROP 2 LAST ROOM RISER1
J 0
(-3375 2100);
DISPLAY 0.829787 (-3375 2100);
PAINT RED (-3375 2100);
DISPLAY INVISIBLE (-3375 2100);
FORCEPROP 2 LAST CDS_LIB standard
J 0
(-2875 2050);
DISPLAY INVISIBLE (-2875 2050);
FORCEPROP 2 LAST BOM_COST IO_SLOT
J 0
(-3375 2150);
DISPLAY 0.829787 (-3375 2150);
DISPLAY INVISIBLE (-3375 2150);
FORCEPROP 1 LAST BODY_TYPE PLUMBING
J 2
(-2875 2000);
DISPLAY 0.702128 (-2875 2000);
PAINT GREEN (-2875 2000);
DISPLAY INVISIBLE (-2875 2000);
FORCEPROP 1 LAST HDL_TAP TRUE
J 2
(-3200 1925);
DISPLAY 0.702128 (-3200 1925);
PAINT GREEN (-3200 1925);
DISPLAY INVISIBLE (-3200 1925);
FORCEPROP 1 LAST PATH I193
J 2
(-2873 2050);
DISPLAY 0.872340 (-2873 2050);
PAINT GREEN (-2873 2050);
DISPLAY INVISIBLE (-2873 2050);
FORCEADD TAP..6
R 2
(-2875 2150);
FORCEPROP 3 LASTPIN (-2925 2150) SIG_NAME P5E_CPU1_P1_TX_DN<7>
J 0
(-2915 2160);
DISPLAY 0.659574 (-2915 2160);
PAINT MONO (-2915 2160);
DISPLAY INVISIBLE (-2915 2160);
FORCEPROP 1 LASTPIN (-2925 2150) BN 7
J 2
(-2873 2158);
DISPLAY 0.489362 (-2873 2158);
PAINT MONO (-2873 2158);
FORCEPROP 2 LAST ROOM RISER1
J 0
(-3375 2200);
DISPLAY 0.829787 (-3375 2200);
PAINT RED (-3375 2200);
DISPLAY INVISIBLE (-3375 2200);
FORCEPROP 2 LAST CDS_LIB standard
J 0
(-2875 2150);
DISPLAY INVISIBLE (-2875 2150);
FORCEPROP 2 LAST BOM_COST IO_SLOT
J 0
(-3375 2250);
DISPLAY 0.829787 (-3375 2250);
DISPLAY INVISIBLE (-3375 2250);
FORCEPROP 1 LAST BODY_TYPE PLUMBING
J 2
(-2875 2100);
DISPLAY 0.702128 (-2875 2100);
PAINT GREEN (-2875 2100);
DISPLAY INVISIBLE (-2875 2100);
FORCEPROP 1 LAST HDL_TAP TRUE
J 2
(-3200 2025);
DISPLAY 0.702128 (-3200 2025);
PAINT GREEN (-3200 2025);
DISPLAY INVISIBLE (-3200 2025);
FORCEPROP 1 LAST PATH I194
J 2
(-2873 2150);
DISPLAY 0.872340 (-2873 2150);
PAINT GREEN (-2873 2150);
DISPLAY INVISIBLE (-2873 2150);
FORCEADD TAP..6
R 2
(-3025 2900);
FORCEPROP 3 LASTPIN (-3075 2900) SIG_NAME P5E_CPU1_P1_TX_DP<0>
J 0
(-3065 2910);
DISPLAY 0.659574 (-3065 2910);
PAINT MONO (-3065 2910);
DISPLAY INVISIBLE (-3065 2910);
FORCEPROP 1 LASTPIN (-3075 2900) BN 0
J 2
(-3023 2908);
DISPLAY 0.489362 (-3023 2908);
PAINT MONO (-3023 2908);
FORCEPROP 2 LAST ROOM RISER1
J 0
(-3525 2950);
DISPLAY 0.829787 (-3525 2950);
PAINT RED (-3525 2950);
DISPLAY INVISIBLE (-3525 2950);
FORCEPROP 2 LAST CDS_LIB mstr_standard
J 0
(-3025 2900);
DISPLAY INVISIBLE (-3025 2900);
FORCEPROP 2 LAST BOM_COST IO_SLOT
J 0
(-3525 3000);
DISPLAY 0.829787 (-3525 3000);
DISPLAY INVISIBLE (-3525 3000);
FORCEPROP 1 LAST BODY_TYPE PLUMBING
J 2
(-3025 2850);
DISPLAY 0.702128 (-3025 2850);
PAINT GREEN (-3025 2850);
DISPLAY INVISIBLE (-3025 2850);
FORCEPROP 1 LAST HDL_TAP TRUE
J 2
(-3350 2775);
DISPLAY 0.702128 (-3350 2775);
PAINT GREEN (-3350 2775);
DISPLAY INVISIBLE (-3350 2775);
FORCEPROP 1 LAST PATH I196
J 2
(-3023 2900);
DISPLAY 0.872340 (-3023 2900);
PAINT GREEN (-3023 2900);
DISPLAY INVISIBLE (-3023 2900);
FORCEADD TAP..6
R 2
(-3025 2700);
FORCEPROP 3 LASTPIN (-3075 2700) SIG_NAME P5E_CPU1_P1_TX_DP<2>
J 0
(-3065 2710);
DISPLAY 0.659574 (-3065 2710);
PAINT MONO (-3065 2710);
DISPLAY INVISIBLE (-3065 2710);
FORCEPROP 1 LASTPIN (-3075 2700) BN 2
J 2
(-3023 2708);
DISPLAY 0.489362 (-3023 2708);
PAINT MONO (-3023 2708);
FORCEPROP 2 LAST ROOM RISER1
J 0
(-3525 2750);
DISPLAY 0.829787 (-3525 2750);
PAINT RED (-3525 2750);
DISPLAY INVISIBLE (-3525 2750);
FORCEPROP 2 LAST CDS_LIB standard
J 0
(-3025 2700);
DISPLAY INVISIBLE (-3025 2700);
FORCEPROP 2 LAST BOM_COST IO_SLOT
J 0
(-3525 2800);
DISPLAY 0.829787 (-3525 2800);
DISPLAY INVISIBLE (-3525 2800);
FORCEPROP 1 LAST BODY_TYPE PLUMBING
J 2
(-3025 2650);
DISPLAY 0.702128 (-3025 2650);
PAINT GREEN (-3025 2650);
DISPLAY INVISIBLE (-3025 2650);
FORCEPROP 1 LAST HDL_TAP TRUE
J 2
(-3350 2575);
DISPLAY 0.702128 (-3350 2575);
PAINT GREEN (-3350 2575);
DISPLAY INVISIBLE (-3350 2575);
FORCEPROP 1 LAST PATH I197
J 2
(-3023 2700);
DISPLAY 0.872340 (-3023 2700);
PAINT GREEN (-3023 2700);
DISPLAY INVISIBLE (-3023 2700);
FORCEADD TAP..6
R 2
(-3025 2800);
FORCEPROP 3 LASTPIN (-3075 2800) SIG_NAME P5E_CPU1_P1_TX_DP<1>
J 0
(-3065 2810);
DISPLAY 0.659574 (-3065 2810);
PAINT MONO (-3065 2810);
DISPLAY INVISIBLE (-3065 2810);
FORCEPROP 1 LASTPIN (-3075 2800) BN 1
J 2
(-3023 2808);
DISPLAY 0.489362 (-3023 2808);
PAINT MONO (-3023 2808);
FORCEPROP 2 LAST ROOM RISER1
J 0
(-3525 2850);
DISPLAY 0.829787 (-3525 2850);
PAINT RED (-3525 2850);
DISPLAY INVISIBLE (-3525 2850);
FORCEPROP 2 LAST CDS_LIB mstr_standard
J 0
(-3025 2800);
DISPLAY INVISIBLE (-3025 2800);
FORCEPROP 2 LAST BOM_COST IO_SLOT
J 0
(-3525 2900);
DISPLAY 0.829787 (-3525 2900);
DISPLAY INVISIBLE (-3525 2900);
FORCEPROP 1 LAST BODY_TYPE PLUMBING
J 2
(-3025 2750);
DISPLAY 0.702128 (-3025 2750);
PAINT GREEN (-3025 2750);
DISPLAY INVISIBLE (-3025 2750);
FORCEPROP 1 LAST HDL_TAP TRUE
J 2
(-3350 2675);
DISPLAY 0.702128 (-3350 2675);
PAINT GREEN (-3350 2675);
DISPLAY INVISIBLE (-3350 2675);
FORCEPROP 1 LAST PATH I198
J 2
(-3023 2800);
DISPLAY 0.872340 (-3023 2800);
PAINT GREEN (-3023 2800);
DISPLAY INVISIBLE (-3023 2800);
FORCEADD TAP..6
R 2
(-3025 2600);
FORCEPROP 3 LASTPIN (-3075 2600) SIG_NAME P5E_CPU1_P1_TX_DP<3>
J 0
(-3065 2610);
DISPLAY 0.659574 (-3065 2610);
PAINT MONO (-3065 2610);
DISPLAY INVISIBLE (-3065 2610);
FORCEPROP 1 LASTPIN (-3075 2600) BN 3
J 2
(-3023 2608);
DISPLAY 0.489362 (-3023 2608);
PAINT MONO (-3023 2608);
FORCEPROP 2 LAST ROOM RISER1
J 0
(-3525 2650);
DISPLAY 0.829787 (-3525 2650);
PAINT RED (-3525 2650);
DISPLAY INVISIBLE (-3525 2650);
FORCEPROP 2 LAST CDS_LIB standard
J 0
(-3025 2600);
DISPLAY INVISIBLE (-3025 2600);
FORCEPROP 2 LAST BOM_COST IO_SLOT
J 0
(-3525 2700);
DISPLAY 0.829787 (-3525 2700);
DISPLAY INVISIBLE (-3525 2700);
FORCEPROP 1 LAST BODY_TYPE PLUMBING
J 2
(-3025 2550);
DISPLAY 0.702128 (-3025 2550);
PAINT GREEN (-3025 2550);
DISPLAY INVISIBLE (-3025 2550);
FORCEPROP 1 LAST HDL_TAP TRUE
J 2
(-3350 2475);
DISPLAY 0.702128 (-3350 2475);
PAINT GREEN (-3350 2475);
DISPLAY INVISIBLE (-3350 2475);
FORCEPROP 1 LAST PATH I199
J 2
(-3023 2600);
DISPLAY 0.872340 (-3023 2600);
PAINT GREEN (-3023 2600);
DISPLAY INVISIBLE (-3023 2600);
FORCEADD TAP..6
R 2
(-3025 2500);
FORCEPROP 3 LASTPIN (-3075 2500) SIG_NAME P5E_CPU1_P1_TX_DP<4>
J 0
(-3065 2510);
DISPLAY 0.659574 (-3065 2510);
PAINT MONO (-3065 2510);
DISPLAY INVISIBLE (-3065 2510);
FORCEPROP 1 LASTPIN (-3075 2500) BN 4
J 2
(-3023 2508);
DISPLAY 0.489362 (-3023 2508);
PAINT MONO (-3023 2508);
FORCEPROP 2 LAST ROOM RISER1
J 0
(-3525 2550);
DISPLAY 0.829787 (-3525 2550);
PAINT RED (-3525 2550);
DISPLAY INVISIBLE (-3525 2550);
FORCEPROP 2 LAST CDS_LIB standard
J 0
(-3025 2500);
DISPLAY INVISIBLE (-3025 2500);
FORCEPROP 2 LAST BOM_COST IO_SLOT
J 0
(-3525 2600);
DISPLAY 0.829787 (-3525 2600);
DISPLAY INVISIBLE (-3525 2600);
FORCEPROP 1 LAST BODY_TYPE PLUMBING
J 2
(-3025 2450);
DISPLAY 0.702128 (-3025 2450);
PAINT GREEN (-3025 2450);
DISPLAY INVISIBLE (-3025 2450);
FORCEPROP 1 LAST HDL_TAP TRUE
J 2
(-3350 2375);
DISPLAY 0.702128 (-3350 2375);
PAINT GREEN (-3350 2375);
DISPLAY INVISIBLE (-3350 2375);
FORCEPROP 1 LAST PATH I200
J 2
(-3023 2500);
DISPLAY 0.872340 (-3023 2500);
PAINT GREEN (-3023 2500);
DISPLAY INVISIBLE (-3023 2500);
FORCEADD TAP..6
R 2
(-3025 2400);
FORCEPROP 3 LASTPIN (-3075 2400) SIG_NAME P5E_CPU1_P1_TX_DP<5>
J 0
(-3065 2410);
DISPLAY 0.659574 (-3065 2410);
PAINT MONO (-3065 2410);
DISPLAY INVISIBLE (-3065 2410);
FORCEPROP 1 LASTPIN (-3075 2400) BN 5
J 2
(-3023 2408);
DISPLAY 0.489362 (-3023 2408);
PAINT MONO (-3023 2408);
FORCEPROP 2 LAST ROOM RISER1
J 0
(-3525 2450);
DISPLAY 0.829787 (-3525 2450);
PAINT RED (-3525 2450);
DISPLAY INVISIBLE (-3525 2450);
FORCEPROP 2 LAST CDS_LIB standard
J 0
(-3025 2400);
DISPLAY INVISIBLE (-3025 2400);
FORCEPROP 2 LAST BOM_COST IO_SLOT
J 0
(-3525 2500);
DISPLAY 0.829787 (-3525 2500);
DISPLAY INVISIBLE (-3525 2500);
FORCEPROP 1 LAST BODY_TYPE PLUMBING
J 2
(-3025 2350);
DISPLAY 0.702128 (-3025 2350);
PAINT GREEN (-3025 2350);
DISPLAY INVISIBLE (-3025 2350);
FORCEPROP 1 LAST HDL_TAP TRUE
J 2
(-3350 2275);
DISPLAY 0.702128 (-3350 2275);
PAINT GREEN (-3350 2275);
DISPLAY INVISIBLE (-3350 2275);
FORCEPROP 1 LAST PATH I201
J 2
(-3023 2400);
DISPLAY 0.872340 (-3023 2400);
PAINT GREEN (-3023 2400);
DISPLAY INVISIBLE (-3023 2400);
FORCEADD TAP..6
R 2
(-3025 2300);
FORCEPROP 3 LASTPIN (-3075 2300) SIG_NAME P5E_CPU1_P1_TX_DP<6>
J 0
(-3065 2310);
DISPLAY 0.659574 (-3065 2310);
PAINT MONO (-3065 2310);
DISPLAY INVISIBLE (-3065 2310);
FORCEPROP 1 LASTPIN (-3075 2300) BN 6
J 2
(-3023 2308);
DISPLAY 0.489362 (-3023 2308);
PAINT MONO (-3023 2308);
FORCEPROP 2 LAST ROOM RISER1
J 0
(-3525 2350);
DISPLAY 0.829787 (-3525 2350);
PAINT RED (-3525 2350);
DISPLAY INVISIBLE (-3525 2350);
FORCEPROP 2 LAST CDS_LIB standard
J 0
(-3025 2300);
DISPLAY INVISIBLE (-3025 2300);
FORCEPROP 2 LAST BOM_COST IO_SLOT
J 0
(-3525 2400);
DISPLAY 0.829787 (-3525 2400);
DISPLAY INVISIBLE (-3525 2400);
FORCEPROP 1 LAST BODY_TYPE PLUMBING
J 2
(-3025 2250);
DISPLAY 0.702128 (-3025 2250);
PAINT GREEN (-3025 2250);
DISPLAY INVISIBLE (-3025 2250);
FORCEPROP 1 LAST HDL_TAP TRUE
J 2
(-3350 2175);
DISPLAY 0.702128 (-3350 2175);
PAINT GREEN (-3350 2175);
DISPLAY INVISIBLE (-3350 2175);
FORCEPROP 1 LAST PATH I202
J 2
(-3023 2300);
DISPLAY 0.872340 (-3023 2300);
PAINT GREEN (-3023 2300);
DISPLAY INVISIBLE (-3023 2300);
FORCEADD TAP..6
R 2
(-3025 2200);
FORCEPROP 3 LASTPIN (-3075 2200) SIG_NAME P5E_CPU1_P1_TX_DP<7>
J 0
(-3065 2210);
DISPLAY 0.659574 (-3065 2210);
PAINT MONO (-3065 2210);
DISPLAY INVISIBLE (-3065 2210);
FORCEPROP 1 LASTPIN (-3075 2200) BN 7
J 2
(-3023 2208);
DISPLAY 0.489362 (-3023 2208);
PAINT MONO (-3023 2208);
FORCEPROP 2 LAST ROOM RISER1
J 0
(-3525 2250);
DISPLAY 0.829787 (-3525 2250);
PAINT RED (-3525 2250);
DISPLAY INVISIBLE (-3525 2250);
FORCEPROP 2 LAST CDS_LIB standard
J 0
(-3025 2200);
DISPLAY INVISIBLE (-3025 2200);
FORCEPROP 2 LAST BOM_COST IO_SLOT
J 0
(-3525 2300);
DISPLAY 0.829787 (-3525 2300);
DISPLAY INVISIBLE (-3525 2300);
FORCEPROP 1 LAST BODY_TYPE PLUMBING
J 2
(-3025 2150);
DISPLAY 0.702128 (-3025 2150);
PAINT GREEN (-3025 2150);
DISPLAY INVISIBLE (-3025 2150);
FORCEPROP 1 LAST HDL_TAP TRUE
J 2
(-3350 2075);
DISPLAY 0.702128 (-3350 2075);
PAINT GREEN (-3350 2075);
DISPLAY INVISIBLE (-3350 2075);
FORCEPROP 1 LAST PATH I203
J 2
(-3023 2200);
DISPLAY 0.872340 (-3023 2200);
PAINT GREEN (-3023 2200);
DISPLAY INVISIBLE (-3023 2200);
FORCEADD TAP..6
R 2
(-3025 2100);
FORCEPROP 3 LASTPIN (-3075 2100) SIG_NAME P5E_CPU1_P1_TX_DP<8>
J 0
(-3065 2110);
DISPLAY 0.659574 (-3065 2110);
PAINT MONO (-3065 2110);
DISPLAY INVISIBLE (-3065 2110);
FORCEPROP 1 LASTPIN (-3075 2100) BN 8
J 2
(-3023 2108);
DISPLAY 0.489362 (-3023 2108);
PAINT MONO (-3023 2108);
FORCEPROP 2 LAST ROOM RISER1
J 0
(-3525 2150);
DISPLAY 0.829787 (-3525 2150);
PAINT RED (-3525 2150);
DISPLAY INVISIBLE (-3525 2150);
FORCEPROP 2 LAST CDS_LIB standard
J 0
(-3025 2100);
DISPLAY INVISIBLE (-3025 2100);
FORCEPROP 2 LAST BOM_COST IO_SLOT
J 0
(-3525 2200);
DISPLAY 0.829787 (-3525 2200);
DISPLAY INVISIBLE (-3525 2200);
FORCEPROP 1 LAST BODY_TYPE PLUMBING
J 2
(-3025 2050);
DISPLAY 0.702128 (-3025 2050);
PAINT GREEN (-3025 2050);
DISPLAY INVISIBLE (-3025 2050);
FORCEPROP 1 LAST HDL_TAP TRUE
J 2
(-3350 1975);
DISPLAY 0.702128 (-3350 1975);
PAINT GREEN (-3350 1975);
DISPLAY INVISIBLE (-3350 1975);
FORCEPROP 1 LAST PATH I204
J 2
(-3023 2100);
DISPLAY 0.872340 (-3023 2100);
PAINT GREEN (-3023 2100);
DISPLAY INVISIBLE (-3023 2100);
FORCEADD TAP..6
R 2
(-2875 1950);
FORCEPROP 3 LASTPIN (-2925 1950) SIG_NAME P5E_CPU1_P1_TX_DN<9>
J 0
(-2915 1960);
DISPLAY 0.659574 (-2915 1960);
PAINT MONO (-2915 1960);
DISPLAY INVISIBLE (-2915 1960);
FORCEPROP 1 LASTPIN (-2925 1950) BN 9
J 2
(-2873 1958);
DISPLAY 0.489362 (-2873 1958);
PAINT MONO (-2873 1958);
FORCEPROP 2 LAST ROOM RISER1
J 0
(-3375 2000);
DISPLAY 0.829787 (-3375 2000);
PAINT RED (-3375 2000);
DISPLAY INVISIBLE (-3375 2000);
FORCEPROP 2 LAST CDS_LIB standard
J 0
(-2875 1950);
DISPLAY INVISIBLE (-2875 1950);
FORCEPROP 2 LAST BOM_COST IO_SLOT
J 0
(-3375 2050);
DISPLAY 0.829787 (-3375 2050);
DISPLAY INVISIBLE (-3375 2050);
FORCEPROP 1 LAST BODY_TYPE PLUMBING
J 2
(-2875 1900);
DISPLAY 0.702128 (-2875 1900);
PAINT GREEN (-2875 1900);
DISPLAY INVISIBLE (-2875 1900);
FORCEPROP 1 LAST HDL_TAP TRUE
J 2
(-3200 1825);
DISPLAY 0.702128 (-3200 1825);
PAINT GREEN (-3200 1825);
DISPLAY INVISIBLE (-3200 1825);
FORCEPROP 1 LAST PATH I205
J 2
(-2873 1950);
DISPLAY 0.872340 (-2873 1950);
PAINT GREEN (-2873 1950);
DISPLAY INVISIBLE (-2873 1950);
FORCEADD TAP..6
R 2
(-2875 1850);
FORCEPROP 3 LASTPIN (-2925 1850) SIG_NAME P5E_CPU1_P1_TX_DN<10>
J 0
(-2915 1860);
DISPLAY 0.659574 (-2915 1860);
PAINT MONO (-2915 1860);
DISPLAY INVISIBLE (-2915 1860);
FORCEPROP 1 LASTPIN (-2925 1850) BN 10
J 2
(-2873 1858);
DISPLAY 0.489362 (-2873 1858);
PAINT MONO (-2873 1858);
FORCEPROP 2 LAST ROOM RISER1
J 0
(-3375 1900);
DISPLAY 0.829787 (-3375 1900);
PAINT RED (-3375 1900);
DISPLAY INVISIBLE (-3375 1900);
FORCEPROP 2 LAST CDS_LIB standard
J 0
(-2875 1850);
DISPLAY INVISIBLE (-2875 1850);
FORCEPROP 2 LAST BOM_COST IO_SLOT
J 0
(-3375 1950);
DISPLAY 0.829787 (-3375 1950);
DISPLAY INVISIBLE (-3375 1950);
FORCEPROP 1 LAST BODY_TYPE PLUMBING
J 2
(-2875 1800);
DISPLAY 0.702128 (-2875 1800);
PAINT GREEN (-2875 1800);
DISPLAY INVISIBLE (-2875 1800);
FORCEPROP 1 LAST HDL_TAP TRUE
J 2
(-3200 1725);
DISPLAY 0.702128 (-3200 1725);
PAINT GREEN (-3200 1725);
DISPLAY INVISIBLE (-3200 1725);
FORCEPROP 1 LAST PATH I206
J 2
(-2873 1850);
DISPLAY 0.872340 (-2873 1850);
PAINT GREEN (-2873 1850);
DISPLAY INVISIBLE (-2873 1850);
FORCEADD TAP..6
R 2
(-2875 1750);
FORCEPROP 3 LASTPIN (-2925 1750) SIG_NAME P5E_CPU1_P1_TX_DN<11>
J 0
(-2915 1760);
DISPLAY 0.659574 (-2915 1760);
PAINT MONO (-2915 1760);
DISPLAY INVISIBLE (-2915 1760);
FORCEPROP 1 LASTPIN (-2925 1750) BN 11
J 2
(-2873 1758);
DISPLAY 0.489362 (-2873 1758);
PAINT MONO (-2873 1758);
FORCEPROP 2 LAST ROOM RISER1
J 0
(-3375 1800);
DISPLAY 0.829787 (-3375 1800);
PAINT RED (-3375 1800);
DISPLAY INVISIBLE (-3375 1800);
FORCEPROP 2 LAST CDS_LIB standard
J 0
(-2875 1750);
DISPLAY INVISIBLE (-2875 1750);
FORCEPROP 2 LAST BOM_COST IO_SLOT
J 0
(-3375 1850);
DISPLAY 0.829787 (-3375 1850);
DISPLAY INVISIBLE (-3375 1850);
FORCEPROP 1 LAST BODY_TYPE PLUMBING
J 2
(-2875 1700);
DISPLAY 0.702128 (-2875 1700);
PAINT GREEN (-2875 1700);
DISPLAY INVISIBLE (-2875 1700);
FORCEPROP 1 LAST HDL_TAP TRUE
J 2
(-3200 1625);
DISPLAY 0.702128 (-3200 1625);
PAINT GREEN (-3200 1625);
DISPLAY INVISIBLE (-3200 1625);
FORCEPROP 1 LAST PATH I207
J 2
(-2873 1750);
DISPLAY 0.872340 (-2873 1750);
PAINT GREEN (-2873 1750);
DISPLAY INVISIBLE (-2873 1750);
FORCEADD TAP..6
R 2
(-2875 1550);
FORCEPROP 3 LASTPIN (-2925 1550) SIG_NAME P5E_CPU1_P1_TX_DN<13>
J 0
(-2915 1560);
DISPLAY 0.659574 (-2915 1560);
PAINT MONO (-2915 1560);
DISPLAY INVISIBLE (-2915 1560);
FORCEPROP 1 LASTPIN (-2925 1550) BN 13
J 2
(-2873 1558);
DISPLAY 0.489362 (-2873 1558);
PAINT MONO (-2873 1558);
FORCEPROP 2 LAST ROOM RISER1
J 0
(-3375 1600);
DISPLAY 0.829787 (-3375 1600);
PAINT RED (-3375 1600);
DISPLAY INVISIBLE (-3375 1600);
FORCEPROP 2 LAST CDS_LIB standard
J 0
(-2875 1550);
DISPLAY INVISIBLE (-2875 1550);
FORCEPROP 2 LAST BOM_COST IO_SLOT
J 0
(-3375 1650);
DISPLAY 0.829787 (-3375 1650);
DISPLAY INVISIBLE (-3375 1650);
FORCEPROP 1 LAST BODY_TYPE PLUMBING
J 2
(-2875 1500);
DISPLAY 0.702128 (-2875 1500);
PAINT GREEN (-2875 1500);
DISPLAY INVISIBLE (-2875 1500);
FORCEPROP 1 LAST HDL_TAP TRUE
J 2
(-3200 1425);
DISPLAY 0.702128 (-3200 1425);
PAINT GREEN (-3200 1425);
DISPLAY INVISIBLE (-3200 1425);
FORCEPROP 1 LAST PATH I208
J 2
(-2873 1550);
DISPLAY 0.872340 (-2873 1550);
PAINT GREEN (-2873 1550);
DISPLAY INVISIBLE (-2873 1550);
FORCEADD TAP..6
R 2
(-2875 1650);
FORCEPROP 3 LASTPIN (-2925 1650) SIG_NAME P5E_CPU1_P1_TX_DN<12>
J 0
(-2915 1660);
DISPLAY 0.659574 (-2915 1660);
PAINT MONO (-2915 1660);
DISPLAY INVISIBLE (-2915 1660);
FORCEPROP 1 LASTPIN (-2925 1650) BN 12
J 2
(-2873 1658);
DISPLAY 0.489362 (-2873 1658);
PAINT MONO (-2873 1658);
FORCEPROP 2 LAST ROOM RISER1
J 0
(-3375 1700);
DISPLAY 0.829787 (-3375 1700);
PAINT RED (-3375 1700);
DISPLAY INVISIBLE (-3375 1700);
FORCEPROP 2 LAST CDS_LIB standard
J 0
(-2875 1650);
DISPLAY INVISIBLE (-2875 1650);
FORCEPROP 2 LAST BOM_COST IO_SLOT
J 0
(-3375 1750);
DISPLAY 0.829787 (-3375 1750);
DISPLAY INVISIBLE (-3375 1750);
FORCEPROP 1 LAST BODY_TYPE PLUMBING
J 2
(-2875 1600);
DISPLAY 0.702128 (-2875 1600);
PAINT GREEN (-2875 1600);
DISPLAY INVISIBLE (-2875 1600);
FORCEPROP 1 LAST HDL_TAP TRUE
J 2
(-3200 1525);
DISPLAY 0.702128 (-3200 1525);
PAINT GREEN (-3200 1525);
DISPLAY INVISIBLE (-3200 1525);
FORCEPROP 1 LAST PATH I209
J 2
(-2873 1650);
DISPLAY 0.872340 (-2873 1650);
PAINT GREEN (-2873 1650);
DISPLAY INVISIBLE (-2873 1650);
FORCEADD TAP..6
R 2
(-2875 1450);
FORCEPROP 3 LASTPIN (-2925 1450) SIG_NAME P5E_CPU1_P1_TX_DN<14>
J 0
(-2915 1460);
DISPLAY 0.659574 (-2915 1460);
PAINT MONO (-2915 1460);
DISPLAY INVISIBLE (-2915 1460);
FORCEPROP 1 LASTPIN (-2925 1450) BN 14
J 2
(-2873 1458);
DISPLAY 0.489362 (-2873 1458);
PAINT MONO (-2873 1458);
FORCEPROP 2 LAST ROOM RISER1
J 0
(-3375 1500);
DISPLAY 0.829787 (-3375 1500);
PAINT RED (-3375 1500);
DISPLAY INVISIBLE (-3375 1500);
FORCEPROP 2 LAST BOM_COST IO_SLOT
J 0
(-3375 1550);
DISPLAY 0.829787 (-3375 1550);
DISPLAY INVISIBLE (-3375 1550);
FORCEPROP 2 LAST CDS_LIB standard
J 0
(-2875 1450);
DISPLAY INVISIBLE (-2875 1450);
FORCEPROP 1 LAST BODY_TYPE PLUMBING
J 2
(-2875 1400);
DISPLAY 0.702128 (-2875 1400);
PAINT GREEN (-2875 1400);
DISPLAY INVISIBLE (-2875 1400);
FORCEPROP 1 LAST HDL_TAP TRUE
J 2
(-3200 1325);
DISPLAY 0.702128 (-3200 1325);
PAINT GREEN (-3200 1325);
DISPLAY INVISIBLE (-3200 1325);
FORCEPROP 1 LAST PATH I210
J 2
(-2873 1450);
DISPLAY 0.872340 (-2873 1450);
PAINT GREEN (-2873 1450);
DISPLAY INVISIBLE (-2873 1450);
FORCEADD TAP..6
R 2
(-2875 1350);
FORCEPROP 3 LASTPIN (-2925 1350) SIG_NAME P5E_CPU1_P1_TX_DN<15>
J 0
(-2915 1360);
DISPLAY 0.659574 (-2915 1360);
PAINT MONO (-2915 1360);
DISPLAY INVISIBLE (-2915 1360);
FORCEPROP 1 LASTPIN (-2925 1350) BN 15
J 2
(-2873 1358);
DISPLAY 0.489362 (-2873 1358);
PAINT MONO (-2873 1358);
FORCEPROP 2 LAST ROOM RISER1
J 0
(-3375 1400);
DISPLAY 0.829787 (-3375 1400);
PAINT RED (-3375 1400);
DISPLAY INVISIBLE (-3375 1400);
FORCEPROP 2 LAST CDS_LIB standard
J 0
(-2875 1350);
DISPLAY INVISIBLE (-2875 1350);
FORCEPROP 2 LAST BOM_COST IO_SLOT
J 0
(-3375 1450);
DISPLAY 0.829787 (-3375 1450);
DISPLAY INVISIBLE (-3375 1450);
FORCEPROP 1 LAST BODY_TYPE PLUMBING
J 2
(-2875 1300);
DISPLAY 0.702128 (-2875 1300);
PAINT GREEN (-2875 1300);
DISPLAY INVISIBLE (-2875 1300);
FORCEPROP 1 LAST HDL_TAP TRUE
J 2
(-3200 1225);
DISPLAY 0.702128 (-3200 1225);
PAINT GREEN (-3200 1225);
DISPLAY INVISIBLE (-3200 1225);
FORCEPROP 1 LAST PATH I211
J 2
(-2873 1350);
DISPLAY 0.872340 (-2873 1350);
PAINT GREEN (-2873 1350);
DISPLAY INVISIBLE (-2873 1350);
FORCEADD TAP..6
R 2
(-3025 2000);
FORCEPROP 3 LASTPIN (-3075 2000) SIG_NAME P5E_CPU1_P1_TX_DP<9>
J 0
(-3065 2010);
DISPLAY 0.659574 (-3065 2010);
PAINT MONO (-3065 2010);
DISPLAY INVISIBLE (-3065 2010);
FORCEPROP 1 LASTPIN (-3075 2000) BN 9
J 2
(-3023 2008);
DISPLAY 0.489362 (-3023 2008);
PAINT MONO (-3023 2008);
FORCEPROP 2 LAST ROOM RISER1
J 0
(-3525 2050);
DISPLAY 0.829787 (-3525 2050);
PAINT RED (-3525 2050);
DISPLAY INVISIBLE (-3525 2050);
FORCEPROP 2 LAST CDS_LIB standard
J 0
(-3025 2000);
DISPLAY INVISIBLE (-3025 2000);
FORCEPROP 2 LAST BOM_COST IO_SLOT
J 0
(-3525 2100);
DISPLAY 0.829787 (-3525 2100);
DISPLAY INVISIBLE (-3525 2100);
FORCEPROP 1 LAST BODY_TYPE PLUMBING
J 2
(-3025 1950);
DISPLAY 0.702128 (-3025 1950);
PAINT GREEN (-3025 1950);
DISPLAY INVISIBLE (-3025 1950);
FORCEPROP 1 LAST HDL_TAP TRUE
J 2
(-3350 1875);
DISPLAY 0.702128 (-3350 1875);
PAINT GREEN (-3350 1875);
DISPLAY INVISIBLE (-3350 1875);
FORCEPROP 1 LAST PATH I212
J 2
(-3023 2000);
DISPLAY 0.872340 (-3023 2000);
PAINT GREEN (-3023 2000);
DISPLAY INVISIBLE (-3023 2000);
FORCEADD TAP..6
R 2
(-3025 1900);
FORCEPROP 3 LASTPIN (-3075 1900) SIG_NAME P5E_CPU1_P1_TX_DP<10>
J 0
(-3065 1910);
DISPLAY 0.659574 (-3065 1910);
PAINT MONO (-3065 1910);
DISPLAY INVISIBLE (-3065 1910);
FORCEPROP 1 LASTPIN (-3075 1900) BN 10
J 2
(-3023 1908);
DISPLAY 0.489362 (-3023 1908);
PAINT MONO (-3023 1908);
FORCEPROP 2 LAST ROOM RISER1
J 0
(-3525 1950);
DISPLAY 0.829787 (-3525 1950);
PAINT RED (-3525 1950);
DISPLAY INVISIBLE (-3525 1950);
FORCEPROP 2 LAST CDS_LIB standard
J 0
(-3025 1900);
DISPLAY INVISIBLE (-3025 1900);
FORCEPROP 2 LAST BOM_COST IO_SLOT
J 0
(-3525 2000);
DISPLAY 0.829787 (-3525 2000);
DISPLAY INVISIBLE (-3525 2000);
FORCEPROP 1 LAST BODY_TYPE PLUMBING
J 2
(-3025 1850);
DISPLAY 0.702128 (-3025 1850);
PAINT GREEN (-3025 1850);
DISPLAY INVISIBLE (-3025 1850);
FORCEPROP 1 LAST HDL_TAP TRUE
J 2
(-3350 1775);
DISPLAY 0.702128 (-3350 1775);
PAINT GREEN (-3350 1775);
DISPLAY INVISIBLE (-3350 1775);
FORCEPROP 1 LAST PATH I213
J 2
(-3023 1900);
DISPLAY 0.872340 (-3023 1900);
PAINT GREEN (-3023 1900);
DISPLAY INVISIBLE (-3023 1900);
FORCEADD TAP..6
R 2
(-3025 1800);
FORCEPROP 3 LASTPIN (-3075 1800) SIG_NAME P5E_CPU1_P1_TX_DP<11>
J 0
(-3065 1810);
DISPLAY 0.659574 (-3065 1810);
PAINT MONO (-3065 1810);
DISPLAY INVISIBLE (-3065 1810);
FORCEPROP 1 LASTPIN (-3075 1800) BN 11
J 2
(-3023 1808);
DISPLAY 0.489362 (-3023 1808);
PAINT MONO (-3023 1808);
FORCEPROP 2 LAST ROOM RISER1
J 0
(-3525 1850);
DISPLAY 0.829787 (-3525 1850);
PAINT RED (-3525 1850);
DISPLAY INVISIBLE (-3525 1850);
FORCEPROP 2 LAST CDS_LIB standard
J 0
(-3025 1800);
DISPLAY INVISIBLE (-3025 1800);
FORCEPROP 2 LAST BOM_COST IO_SLOT
J 0
(-3525 1900);
DISPLAY 0.829787 (-3525 1900);
DISPLAY INVISIBLE (-3525 1900);
FORCEPROP 1 LAST BODY_TYPE PLUMBING
J 2
(-3025 1750);
DISPLAY 0.702128 (-3025 1750);
PAINT GREEN (-3025 1750);
DISPLAY INVISIBLE (-3025 1750);
FORCEPROP 1 LAST HDL_TAP TRUE
J 2
(-3350 1675);
DISPLAY 0.702128 (-3350 1675);
PAINT GREEN (-3350 1675);
DISPLAY INVISIBLE (-3350 1675);
FORCEPROP 1 LAST PATH I214
J 2
(-3023 1800);
DISPLAY 0.872340 (-3023 1800);
PAINT GREEN (-3023 1800);
DISPLAY INVISIBLE (-3023 1800);
FORCEADD TAP..6
R 2
(-3025 1700);
FORCEPROP 3 LASTPIN (-3075 1700) SIG_NAME P5E_CPU1_P1_TX_DP<12>
J 0
(-3065 1710);
DISPLAY 0.659574 (-3065 1710);
PAINT MONO (-3065 1710);
DISPLAY INVISIBLE (-3065 1710);
FORCEPROP 1 LASTPIN (-3075 1700) BN 12
J 2
(-3023 1708);
DISPLAY 0.489362 (-3023 1708);
PAINT MONO (-3023 1708);
FORCEPROP 2 LAST ROOM RISER1
J 0
(-3525 1750);
DISPLAY 0.829787 (-3525 1750);
PAINT RED (-3525 1750);
DISPLAY INVISIBLE (-3525 1750);
FORCEPROP 2 LAST CDS_LIB standard
J 0
(-3025 1700);
DISPLAY INVISIBLE (-3025 1700);
FORCEPROP 2 LAST BOM_COST IO_SLOT
J 0
(-3525 1800);
DISPLAY 0.829787 (-3525 1800);
DISPLAY INVISIBLE (-3525 1800);
FORCEPROP 1 LAST BODY_TYPE PLUMBING
J 2
(-3025 1650);
DISPLAY 0.702128 (-3025 1650);
PAINT GREEN (-3025 1650);
DISPLAY INVISIBLE (-3025 1650);
FORCEPROP 1 LAST HDL_TAP TRUE
J 2
(-3350 1575);
DISPLAY 0.702128 (-3350 1575);
PAINT GREEN (-3350 1575);
DISPLAY INVISIBLE (-3350 1575);
FORCEPROP 1 LAST PATH I215
J 2
(-3023 1700);
DISPLAY 0.872340 (-3023 1700);
PAINT GREEN (-3023 1700);
DISPLAY INVISIBLE (-3023 1700);
FORCEADD TAP..6
R 2
(-3025 1600);
FORCEPROP 3 LASTPIN (-3075 1600) SIG_NAME P5E_CPU1_P1_TX_DP<13>
J 0
(-3065 1610);
DISPLAY 0.659574 (-3065 1610);
PAINT MONO (-3065 1610);
DISPLAY INVISIBLE (-3065 1610);
FORCEPROP 1 LASTPIN (-3075 1600) BN 13
J 2
(-3023 1608);
DISPLAY 0.489362 (-3023 1608);
PAINT MONO (-3023 1608);
FORCEPROP 2 LAST ROOM RISER1
J 0
(-3525 1650);
DISPLAY 0.829787 (-3525 1650);
PAINT RED (-3525 1650);
DISPLAY INVISIBLE (-3525 1650);
FORCEPROP 2 LAST CDS_LIB standard
J 0
(-3025 1600);
DISPLAY INVISIBLE (-3025 1600);
FORCEPROP 2 LAST BOM_COST IO_SLOT
J 0
(-3525 1700);
DISPLAY 0.829787 (-3525 1700);
DISPLAY INVISIBLE (-3525 1700);
FORCEPROP 1 LAST BODY_TYPE PLUMBING
J 2
(-3025 1550);
DISPLAY 0.702128 (-3025 1550);
PAINT GREEN (-3025 1550);
DISPLAY INVISIBLE (-3025 1550);
FORCEPROP 1 LAST HDL_TAP TRUE
J 2
(-3350 1475);
DISPLAY 0.702128 (-3350 1475);
PAINT GREEN (-3350 1475);
DISPLAY INVISIBLE (-3350 1475);
FORCEPROP 1 LAST PATH I216
J 2
(-3023 1600);
DISPLAY 0.872340 (-3023 1600);
PAINT GREEN (-3023 1600);
DISPLAY INVISIBLE (-3023 1600);
FORCEADD TAP..6
R 2
(-3025 1500);
FORCEPROP 3 LASTPIN (-3075 1500) SIG_NAME P5E_CPU1_P1_TX_DP<14>
J 0
(-3065 1510);
DISPLAY 0.659574 (-3065 1510);
PAINT MONO (-3065 1510);
DISPLAY INVISIBLE (-3065 1510);
FORCEPROP 1 LASTPIN (-3075 1500) BN 14
J 2
(-3023 1508);
DISPLAY 0.489362 (-3023 1508);
PAINT MONO (-3023 1508);
FORCEPROP 2 LAST ROOM RISER1
J 0
(-3525 1550);
DISPLAY 0.829787 (-3525 1550);
PAINT RED (-3525 1550);
DISPLAY INVISIBLE (-3525 1550);
FORCEPROP 2 LAST CDS_LIB standard
J 0
(-3025 1500);
DISPLAY INVISIBLE (-3025 1500);
FORCEPROP 2 LAST BOM_COST IO_SLOT
J 0
(-3525 1600);
DISPLAY 0.829787 (-3525 1600);
DISPLAY INVISIBLE (-3525 1600);
FORCEPROP 1 LAST BODY_TYPE PLUMBING
J 2
(-3025 1450);
DISPLAY 0.702128 (-3025 1450);
PAINT GREEN (-3025 1450);
DISPLAY INVISIBLE (-3025 1450);
FORCEPROP 1 LAST HDL_TAP TRUE
J 2
(-3350 1375);
DISPLAY 0.702128 (-3350 1375);
PAINT GREEN (-3350 1375);
DISPLAY INVISIBLE (-3350 1375);
FORCEPROP 1 LAST PATH I217
J 2
(-3023 1500);
DISPLAY 0.872340 (-3023 1500);
PAINT GREEN (-3023 1500);
DISPLAY INVISIBLE (-3023 1500);
FORCEADD TAP..6
R 2
(-3025 1400);
FORCEPROP 3 LASTPIN (-3075 1400) SIG_NAME P5E_CPU1_P1_TX_DP<15>
J 0
(-3065 1410);
DISPLAY 0.659574 (-3065 1410);
PAINT MONO (-3065 1410);
DISPLAY INVISIBLE (-3065 1410);
FORCEPROP 1 LASTPIN (-3075 1400) BN 15
J 2
(-3023 1408);
DISPLAY 0.489362 (-3023 1408);
PAINT MONO (-3023 1408);
FORCEPROP 2 LAST ROOM RISER1
J 0
(-3525 1450);
DISPLAY 0.829787 (-3525 1450);
PAINT RED (-3525 1450);
DISPLAY INVISIBLE (-3525 1450);
FORCEPROP 2 LAST CDS_LIB standard
J 0
(-3025 1400);
DISPLAY INVISIBLE (-3025 1400);
FORCEPROP 2 LAST BOM_COST IO_SLOT
J 0
(-3525 1500);
DISPLAY 0.829787 (-3525 1500);
DISPLAY INVISIBLE (-3525 1500);
FORCEPROP 1 LAST BODY_TYPE PLUMBING
J 2
(-3025 1350);
DISPLAY 0.702128 (-3025 1350);
PAINT GREEN (-3025 1350);
DISPLAY INVISIBLE (-3025 1350);
FORCEPROP 1 LAST HDL_TAP TRUE
J 2
(-3350 1275);
DISPLAY 0.702128 (-3350 1275);
PAINT GREEN (-3350 1275);
DISPLAY INVISIBLE (-3350 1275);
FORCEPROP 1 LAST PATH I218
J 2
(-3023 1400);
DISPLAY 0.872340 (-3023 1400);
PAINT GREEN (-3023 1400);
DISPLAY INVISIBLE (-3023 1400);
FORCEADD TAP..6
(-6450 5550);
FORCEPROP 3 LASTPIN (-6400 5550) SIG_NAME P5E_CPU1_P0_RX_DP<0>
J 0
(-6390 5560);
DISPLAY 0.659574 (-6390 5560);
PAINT MONO (-6390 5560);
DISPLAY INVISIBLE (-6390 5560);
FORCEPROP 1 LASTPIN (-6400 5550) BN 0
J 0
(-6452 5558);
DISPLAY 0.489362 (-6452 5558);
PAINT MONO (-6452 5558);
FORCEPROP 2 LAST CDS_LIB mstr_standard
J 0
(-6450 5550);
DISPLAY INVISIBLE (-6450 5550);
FORCEPROP 1 LAST BODY_TYPE PLUMBING
J 0
(-6450 5500);
DISPLAY 0.574468 (-6450 5500);
PAINT GREEN (-6450 5500);
DISPLAY INVISIBLE (-6450 5500);
FORCEPROP 1 LAST HDL_TAP TRUE
J 0
(-6125 5425);
DISPLAY 0.574468 (-6125 5425);
PAINT GREEN (-6125 5425);
DISPLAY INVISIBLE (-6125 5425);
FORCEPROP 1 LAST PATH I219
J 0
(-6452 5550);
DISPLAY 0.872340 (-6452 5550);
PAINT GREEN (-6452 5550);
DISPLAY INVISIBLE (-6452 5550);
FORCEADD TAP..6
(-6450 5350);
FORCEPROP 3 LASTPIN (-6400 5350) SIG_NAME P5E_CPU1_P0_RX_DP<2>
J 0
(-6390 5360);
DISPLAY 0.659574 (-6390 5360);
PAINT MONO (-6390 5360);
DISPLAY INVISIBLE (-6390 5360);
FORCEPROP 1 LASTPIN (-6400 5350) BN 2
J 0
(-6452 5358);
DISPLAY 0.489362 (-6452 5358);
PAINT MONO (-6452 5358);
FORCEPROP 2 LAST CDS_LIB mstr_standard
J 0
(-6450 5350);
DISPLAY INVISIBLE (-6450 5350);
FORCEPROP 1 LAST BODY_TYPE PLUMBING
J 0
(-6450 5300);
DISPLAY 0.574468 (-6450 5300);
PAINT GREEN (-6450 5300);
DISPLAY INVISIBLE (-6450 5300);
FORCEPROP 1 LAST HDL_TAP TRUE
J 0
(-6125 5225);
DISPLAY 0.574468 (-6125 5225);
PAINT GREEN (-6125 5225);
DISPLAY INVISIBLE (-6125 5225);
FORCEPROP 1 LAST PATH I220
J 0
(-6452 5350);
DISPLAY 0.872340 (-6452 5350);
PAINT GREEN (-6452 5350);
DISPLAY INVISIBLE (-6452 5350);
FORCEADD TAP..6
(-6450 5450);
FORCEPROP 3 LASTPIN (-6400 5450) SIG_NAME P5E_CPU1_P0_RX_DP<1>
J 0
(-6390 5460);
DISPLAY 0.659574 (-6390 5460);
PAINT MONO (-6390 5460);
DISPLAY INVISIBLE (-6390 5460);
FORCEPROP 1 LASTPIN (-6400 5450) BN 1
J 0
(-6452 5458);
DISPLAY 0.489362 (-6452 5458);
PAINT MONO (-6452 5458);
FORCEPROP 2 LAST CDS_LIB mstr_standard
J 0
(-6450 5450);
DISPLAY INVISIBLE (-6450 5450);
FORCEPROP 1 LAST BODY_TYPE PLUMBING
J 0
(-6450 5400);
DISPLAY 0.574468 (-6450 5400);
PAINT GREEN (-6450 5400);
DISPLAY INVISIBLE (-6450 5400);
FORCEPROP 1 LAST HDL_TAP TRUE
J 0
(-6125 5325);
DISPLAY 0.574468 (-6125 5325);
PAINT GREEN (-6125 5325);
DISPLAY INVISIBLE (-6125 5325);
FORCEPROP 1 LAST PATH I221
J 0
(-6452 5450);
DISPLAY 0.872340 (-6452 5450);
PAINT GREEN (-6452 5450);
DISPLAY INVISIBLE (-6452 5450);
FORCEADD TAP..6
(-6450 5250);
FORCEPROP 3 LASTPIN (-6400 5250) SIG_NAME P5E_CPU1_P0_RX_DP<3>
J 0
(-6390 5260);
DISPLAY 0.659574 (-6390 5260);
PAINT MONO (-6390 5260);
DISPLAY INVISIBLE (-6390 5260);
FORCEPROP 1 LASTPIN (-6400 5250) BN 3
J 0
(-6452 5258);
DISPLAY 0.489362 (-6452 5258);
PAINT MONO (-6452 5258);
FORCEPROP 2 LAST CDS_LIB standard
J 0
(-6450 5250);
DISPLAY INVISIBLE (-6450 5250);
FORCEPROP 1 LAST BODY_TYPE PLUMBING
J 0
(-6450 5200);
DISPLAY 0.574468 (-6450 5200);
PAINT GREEN (-6450 5200);
DISPLAY INVISIBLE (-6450 5200);
FORCEPROP 1 LAST HDL_TAP TRUE
J 0
(-6125 5125);
DISPLAY 0.574468 (-6125 5125);
PAINT GREEN (-6125 5125);
DISPLAY INVISIBLE (-6125 5125);
FORCEPROP 1 LAST PATH I222
J 0
(-6452 5250);
DISPLAY 0.872340 (-6452 5250);
PAINT GREEN (-6452 5250);
DISPLAY INVISIBLE (-6452 5250);
FORCEADD TAP..6
(-6450 5150);
FORCEPROP 3 LASTPIN (-6400 5150) SIG_NAME P5E_CPU1_P0_RX_DP<4>
J 0
(-6390 5160);
DISPLAY 0.659574 (-6390 5160);
PAINT MONO (-6390 5160);
DISPLAY INVISIBLE (-6390 5160);
FORCEPROP 1 LASTPIN (-6400 5150) BN 4
J 0
(-6452 5158);
DISPLAY 0.489362 (-6452 5158);
PAINT MONO (-6452 5158);
FORCEPROP 2 LAST CDS_LIB standard
J 0
(-6450 5150);
DISPLAY INVISIBLE (-6450 5150);
FORCEPROP 1 LAST BODY_TYPE PLUMBING
J 0
(-6450 5100);
DISPLAY 0.574468 (-6450 5100);
PAINT GREEN (-6450 5100);
DISPLAY INVISIBLE (-6450 5100);
FORCEPROP 1 LAST HDL_TAP TRUE
J 0
(-6125 5025);
DISPLAY 0.574468 (-6125 5025);
PAINT GREEN (-6125 5025);
DISPLAY INVISIBLE (-6125 5025);
FORCEPROP 1 LAST PATH I223
J 0
(-6452 5150);
DISPLAY 0.872340 (-6452 5150);
PAINT GREEN (-6452 5150);
DISPLAY INVISIBLE (-6452 5150);
FORCEADD TAP..6
(-6450 5050);
FORCEPROP 3 LASTPIN (-6400 5050) SIG_NAME P5E_CPU1_P0_RX_DP<5>
J 0
(-6390 5060);
DISPLAY 0.659574 (-6390 5060);
PAINT MONO (-6390 5060);
DISPLAY INVISIBLE (-6390 5060);
FORCEPROP 1 LASTPIN (-6400 5050) BN 5
J 0
(-6452 5058);
DISPLAY 0.489362 (-6452 5058);
PAINT MONO (-6452 5058);
FORCEPROP 2 LAST CDS_LIB standard
J 0
(-6450 5050);
DISPLAY INVISIBLE (-6450 5050);
FORCEPROP 1 LAST BODY_TYPE PLUMBING
J 0
(-6450 5000);
DISPLAY 0.574468 (-6450 5000);
PAINT GREEN (-6450 5000);
DISPLAY INVISIBLE (-6450 5000);
FORCEPROP 1 LAST HDL_TAP TRUE
J 0
(-6125 4925);
DISPLAY 0.574468 (-6125 4925);
PAINT GREEN (-6125 4925);
DISPLAY INVISIBLE (-6125 4925);
FORCEPROP 1 LAST PATH I228
J 0
(-6452 5050);
DISPLAY 0.872340 (-6452 5050);
PAINT GREEN (-6452 5050);
DISPLAY INVISIBLE (-6452 5050);
FORCEADD TAP..6
(-6450 4850);
FORCEPROP 3 LASTPIN (-6400 4850) SIG_NAME P5E_CPU1_P0_RX_DP<7>
J 0
(-6390 4860);
DISPLAY 0.659574 (-6390 4860);
PAINT MONO (-6390 4860);
DISPLAY INVISIBLE (-6390 4860);
FORCEPROP 1 LASTPIN (-6400 4850) BN 7
J 0
(-6452 4858);
DISPLAY 0.489362 (-6452 4858);
PAINT MONO (-6452 4858);
FORCEPROP 2 LAST CDS_LIB standard
J 0
(-6450 4850);
DISPLAY INVISIBLE (-6450 4850);
FORCEPROP 1 LAST BODY_TYPE PLUMBING
J 0
(-6450 4800);
DISPLAY 0.574468 (-6450 4800);
PAINT GREEN (-6450 4800);
DISPLAY INVISIBLE (-6450 4800);
FORCEPROP 1 LAST HDL_TAP TRUE
J 0
(-6125 4725);
DISPLAY 0.574468 (-6125 4725);
PAINT GREEN (-6125 4725);
DISPLAY INVISIBLE (-6125 4725);
FORCEPROP 1 LAST PATH I229
J 0
(-6452 4850);
DISPLAY 0.872340 (-6452 4850);
PAINT GREEN (-6452 4850);
DISPLAY INVISIBLE (-6452 4850);
FORCEADD TAP..6
(-6450 4950);
FORCEPROP 3 LASTPIN (-6400 4950) SIG_NAME P5E_CPU1_P0_RX_DP<6>
J 0
(-6390 4960);
DISPLAY 0.659574 (-6390 4960);
PAINT MONO (-6390 4960);
DISPLAY INVISIBLE (-6390 4960);
FORCEPROP 1 LASTPIN (-6400 4950) BN 6
J 0
(-6452 4958);
DISPLAY 0.489362 (-6452 4958);
PAINT MONO (-6452 4958);
FORCEPROP 2 LAST CDS_LIB standard
J 0
(-6450 4950);
DISPLAY INVISIBLE (-6450 4950);
FORCEPROP 1 LAST BODY_TYPE PLUMBING
J 0
(-6450 4900);
DISPLAY 0.574468 (-6450 4900);
PAINT GREEN (-6450 4900);
DISPLAY INVISIBLE (-6450 4900);
FORCEPROP 1 LAST HDL_TAP TRUE
J 0
(-6125 4825);
DISPLAY 0.574468 (-6125 4825);
PAINT GREEN (-6125 4825);
DISPLAY INVISIBLE (-6125 4825);
FORCEPROP 1 LAST PATH I230
J 0
(-6452 4950);
DISPLAY 0.872340 (-6452 4950);
PAINT GREEN (-6452 4950);
DISPLAY INVISIBLE (-6452 4950);
FORCEADD TAP..6
(-6450 4750);
FORCEPROP 3 LASTPIN (-6400 4750) SIG_NAME P5E_CPU1_P0_RX_DP<8>
J 0
(-6390 4760);
DISPLAY 0.659574 (-6390 4760);
PAINT MONO (-6390 4760);
DISPLAY INVISIBLE (-6390 4760);
FORCEPROP 1 LASTPIN (-6400 4750) BN 8
J 0
(-6452 4758);
DISPLAY 0.489362 (-6452 4758);
PAINT MONO (-6452 4758);
FORCEPROP 2 LAST CDS_LIB standard
J 0
(-6450 4750);
DISPLAY INVISIBLE (-6450 4750);
FORCEPROP 1 LAST BODY_TYPE PLUMBING
J 0
(-6450 4700);
DISPLAY 0.574468 (-6450 4700);
PAINT GREEN (-6450 4700);
DISPLAY INVISIBLE (-6450 4700);
FORCEPROP 1 LAST HDL_TAP TRUE
J 0
(-6125 4625);
DISPLAY 0.574468 (-6125 4625);
PAINT GREEN (-6125 4625);
DISPLAY INVISIBLE (-6125 4625);
FORCEPROP 1 LAST PATH I231
J 0
(-6452 4750);
DISPLAY 0.872340 (-6452 4750);
PAINT GREEN (-6452 4750);
DISPLAY INVISIBLE (-6452 4750);
FORCEADD TAP..6
(-6450 4650);
FORCEPROP 3 LASTPIN (-6400 4650) SIG_NAME P5E_CPU1_P0_RX_DP<9>
J 0
(-6390 4660);
DISPLAY 0.659574 (-6390 4660);
PAINT MONO (-6390 4660);
DISPLAY INVISIBLE (-6390 4660);
FORCEPROP 1 LASTPIN (-6400 4650) BN 9
J 0
(-6452 4658);
DISPLAY 0.489362 (-6452 4658);
PAINT MONO (-6452 4658);
FORCEPROP 2 LAST CDS_LIB standard
J 0
(-6450 4650);
DISPLAY INVISIBLE (-6450 4650);
FORCEPROP 1 LAST BODY_TYPE PLUMBING
J 0
(-6450 4600);
DISPLAY 0.574468 (-6450 4600);
PAINT GREEN (-6450 4600);
DISPLAY INVISIBLE (-6450 4600);
FORCEPROP 1 LAST HDL_TAP TRUE
J 0
(-6125 4525);
DISPLAY 0.574468 (-6125 4525);
PAINT GREEN (-6125 4525);
DISPLAY INVISIBLE (-6125 4525);
FORCEPROP 1 LAST PATH I232
J 0
(-6452 4650);
DISPLAY 0.872340 (-6452 4650);
PAINT GREEN (-6452 4650);
DISPLAY INVISIBLE (-6452 4650);
FORCEADD TAP..6
(-6450 4450);
FORCEPROP 3 LASTPIN (-6400 4450) SIG_NAME P5E_CPU1_P0_RX_DP<11>
J 0
(-6390 4460);
DISPLAY 0.659574 (-6390 4460);
PAINT MONO (-6390 4460);
DISPLAY INVISIBLE (-6390 4460);
FORCEPROP 1 LASTPIN (-6400 4450) BN 11
J 0
(-6452 4458);
DISPLAY 0.489362 (-6452 4458);
PAINT MONO (-6452 4458);
FORCEPROP 2 LAST CDS_LIB standard
J 0
(-6450 4450);
DISPLAY INVISIBLE (-6450 4450);
FORCEPROP 1 LAST BODY_TYPE PLUMBING
J 0
(-6450 4400);
DISPLAY 0.574468 (-6450 4400);
PAINT GREEN (-6450 4400);
DISPLAY INVISIBLE (-6450 4400);
FORCEPROP 1 LAST HDL_TAP TRUE
J 0
(-6125 4325);
DISPLAY 0.574468 (-6125 4325);
PAINT GREEN (-6125 4325);
DISPLAY INVISIBLE (-6125 4325);
FORCEPROP 1 LAST PATH I238
J 0
(-6452 4450);
DISPLAY 0.872340 (-6452 4450);
PAINT GREEN (-6452 4450);
DISPLAY INVISIBLE (-6452 4450);
FORCEADD TAP..6
(-6450 4550);
FORCEPROP 3 LASTPIN (-6400 4550) SIG_NAME P5E_CPU1_P0_RX_DP<10>
J 0
(-6390 4560);
DISPLAY 0.659574 (-6390 4560);
PAINT MONO (-6390 4560);
DISPLAY INVISIBLE (-6390 4560);
FORCEPROP 1 LASTPIN (-6400 4550) BN 10
J 0
(-6452 4558);
DISPLAY 0.489362 (-6452 4558);
PAINT MONO (-6452 4558);
FORCEPROP 2 LAST CDS_LIB standard
J 0
(-6450 4550);
DISPLAY INVISIBLE (-6450 4550);
FORCEPROP 1 LAST BODY_TYPE PLUMBING
J 0
(-6450 4500);
DISPLAY 0.574468 (-6450 4500);
PAINT GREEN (-6450 4500);
DISPLAY INVISIBLE (-6450 4500);
FORCEPROP 1 LAST HDL_TAP TRUE
J 0
(-6125 4425);
DISPLAY 0.574468 (-6125 4425);
PAINT GREEN (-6125 4425);
DISPLAY INVISIBLE (-6125 4425);
FORCEPROP 1 LAST PATH I239
J 0
(-6452 4550);
DISPLAY 0.872340 (-6452 4550);
PAINT GREEN (-6452 4550);
DISPLAY INVISIBLE (-6452 4550);
FORCEADD TAP..6
(-6450 4350);
FORCEPROP 3 LASTPIN (-6400 4350) SIG_NAME P5E_CPU1_P0_RX_DP<12>
J 0
(-6390 4360);
DISPLAY 0.659574 (-6390 4360);
PAINT MONO (-6390 4360);
DISPLAY INVISIBLE (-6390 4360);
FORCEPROP 1 LASTPIN (-6400 4350) BN 12
J 0
(-6452 4358);
DISPLAY 0.489362 (-6452 4358);
PAINT MONO (-6452 4358);
FORCEPROP 2 LAST CDS_LIB standard
J 0
(-6450 4350);
DISPLAY INVISIBLE (-6450 4350);
FORCEPROP 1 LAST BODY_TYPE PLUMBING
J 0
(-6450 4300);
DISPLAY 0.574468 (-6450 4300);
PAINT GREEN (-6450 4300);
DISPLAY INVISIBLE (-6450 4300);
FORCEPROP 1 LAST HDL_TAP TRUE
J 0
(-6125 4225);
DISPLAY 0.574468 (-6125 4225);
PAINT GREEN (-6125 4225);
DISPLAY INVISIBLE (-6125 4225);
FORCEPROP 1 LAST PATH I240
J 0
(-6452 4350);
DISPLAY 0.872340 (-6452 4350);
PAINT GREEN (-6452 4350);
DISPLAY INVISIBLE (-6452 4350);
FORCEADD TAP..6
(-6450 4250);
FORCEPROP 3 LASTPIN (-6400 4250) SIG_NAME P5E_CPU1_P0_RX_DP<13>
J 0
(-6390 4260);
DISPLAY 0.659574 (-6390 4260);
PAINT MONO (-6390 4260);
DISPLAY INVISIBLE (-6390 4260);
FORCEPROP 1 LASTPIN (-6400 4250) BN 13
J 0
(-6452 4258);
DISPLAY 0.489362 (-6452 4258);
PAINT MONO (-6452 4258);
FORCEPROP 2 LAST CDS_LIB standard
J 0
(-6450 4250);
DISPLAY INVISIBLE (-6450 4250);
FORCEPROP 1 LAST BODY_TYPE PLUMBING
J 0
(-6450 4200);
DISPLAY 0.574468 (-6450 4200);
PAINT GREEN (-6450 4200);
DISPLAY INVISIBLE (-6450 4200);
FORCEPROP 1 LAST HDL_TAP TRUE
J 0
(-6125 4125);
DISPLAY 0.574468 (-6125 4125);
PAINT GREEN (-6125 4125);
DISPLAY INVISIBLE (-6125 4125);
FORCEPROP 1 LAST PATH I241
J 0
(-6452 4250);
DISPLAY 0.872340 (-6452 4250);
PAINT GREEN (-6452 4250);
DISPLAY INVISIBLE (-6452 4250);
FORCEADD TAP..6
(-6450 4150);
FORCEPROP 3 LASTPIN (-6400 4150) SIG_NAME P5E_CPU1_P0_RX_DP<14>
J 0
(-6390 4160);
DISPLAY 0.659574 (-6390 4160);
PAINT MONO (-6390 4160);
DISPLAY INVISIBLE (-6390 4160);
FORCEPROP 1 LASTPIN (-6400 4150) BN 14
J 0
(-6452 4158);
DISPLAY 0.489362 (-6452 4158);
PAINT MONO (-6452 4158);
FORCEPROP 2 LAST CDS_LIB standard
J 0
(-6450 4150);
DISPLAY INVISIBLE (-6450 4150);
FORCEPROP 1 LAST BODY_TYPE PLUMBING
J 0
(-6450 4100);
DISPLAY 0.574468 (-6450 4100);
PAINT GREEN (-6450 4100);
DISPLAY INVISIBLE (-6450 4100);
FORCEPROP 1 LAST HDL_TAP TRUE
J 0
(-6125 4025);
DISPLAY 0.574468 (-6125 4025);
PAINT GREEN (-6125 4025);
DISPLAY INVISIBLE (-6125 4025);
FORCEPROP 1 LAST PATH I242
J 0
(-6452 4150);
DISPLAY 0.872340 (-6452 4150);
PAINT GREEN (-6452 4150);
DISPLAY INVISIBLE (-6452 4150);
FORCEADD OFFPAGE..1
(-7550 5775);
FORCEPROP 2 LAST $XR0 318 
J 0
(-7802 5775);
DISPLAY 0.638298 (-7802 5775);
PAINT MONO (-7802 5775);
FORCEPROP 2 LAST CDS_LIB standard
J 0
(-7550 5775);
DISPLAY INVISIBLE (-7550 5775);
FORCEPROP 1 LAST OFFPAGE TRUE
J 0
(-7225 5650);
DISPLAY 0.872340 (-7225 5650);
PAINT GREEN (-7225 5650);
DISPLAY INVISIBLE (-7225 5650);
FORCEPROP 1 LAST COMMENT_BODY TRUE
J 0
(-7425 5675);
DISPLAY 0.872340 (-7425 5675);
PAINT GREEN (-7425 5675);
DISPLAY INVISIBLE (-7425 5675);
FORCEPROP 2 LAST PATH I249
J 0
(-7800 5825);
DISPLAY 1.021277 (-7800 5825);
DISPLAY INVISIBLE (-7800 5825);
FORCEADD TAP..6
(-6450 4050);
FORCEPROP 3 LASTPIN (-6400 4050) SIG_NAME P5E_CPU1_P0_RX_DP<15>
J 0
(-6390 4060);
DISPLAY 0.659574 (-6390 4060);
PAINT MONO (-6390 4060);
DISPLAY INVISIBLE (-6390 4060);
FORCEPROP 1 LASTPIN (-6400 4050) BN 15
J 0
(-6452 4058);
DISPLAY 0.489362 (-6452 4058);
PAINT MONO (-6452 4058);
FORCEPROP 2 LAST CDS_LIB standard
J 0
(-6450 4050);
DISPLAY INVISIBLE (-6450 4050);
FORCEPROP 1 LAST BODY_TYPE PLUMBING
J 0
(-6450 4000);
DISPLAY 0.574468 (-6450 4000);
PAINT GREEN (-6450 4000);
DISPLAY INVISIBLE (-6450 4000);
FORCEPROP 1 LAST HDL_TAP TRUE
J 0
(-6125 3925);
DISPLAY 0.574468 (-6125 3925);
PAINT GREEN (-6125 3925);
DISPLAY INVISIBLE (-6125 3925);
FORCEPROP 1 LAST PATH I253
J 0
(-6452 4050);
DISPLAY 0.872340 (-6452 4050);
PAINT GREEN (-6452 4050);
DISPLAY INVISIBLE (-6452 4050);
FORCEADD TAP..6
(-6450 2600);
FORCEPROP 3 LASTPIN (-6400 2600) SIG_NAME P5E_CPU1_P1_RX_DP<3>
J 0
(-6390 2610);
DISPLAY 0.659574 (-6390 2610);
PAINT MONO (-6390 2610);
DISPLAY INVISIBLE (-6390 2610);
FORCEPROP 1 LASTPIN (-6400 2600) BN 3
J 0
(-6452 2608);
DISPLAY 0.489362 (-6452 2608);
PAINT MONO (-6452 2608);
FORCEPROP 2 LAST CDS_LIB standard
J 0
(-6450 2600);
DISPLAY INVISIBLE (-6450 2600);
FORCEPROP 1 LAST BODY_TYPE PLUMBING
J 0
(-6450 2550);
DISPLAY 0.574468 (-6450 2550);
PAINT GREEN (-6450 2550);
DISPLAY INVISIBLE (-6450 2550);
FORCEPROP 1 LAST HDL_TAP TRUE
J 0
(-6125 2475);
DISPLAY 0.574468 (-6125 2475);
PAINT GREEN (-6125 2475);
DISPLAY INVISIBLE (-6125 2475);
FORCEPROP 1 LAST PATH I255
J 0
(-6452 2600);
DISPLAY 0.872340 (-6452 2600);
PAINT GREEN (-6452 2600);
DISPLAY INVISIBLE (-6452 2600);
FORCEADD TAP..6
(-6450 2700);
FORCEPROP 3 LASTPIN (-6400 2700) SIG_NAME P5E_CPU1_P1_RX_DP<2>
J 0
(-6390 2710);
DISPLAY 0.659574 (-6390 2710);
PAINT MONO (-6390 2710);
DISPLAY INVISIBLE (-6390 2710);
FORCEPROP 1 LASTPIN (-6400 2700) BN 2
J 0
(-6452 2708);
DISPLAY 0.489362 (-6452 2708);
PAINT MONO (-6452 2708);
FORCEPROP 2 LAST CDS_LIB mstr_standard
J 0
(-6450 2700);
DISPLAY INVISIBLE (-6450 2700);
FORCEPROP 1 LAST BODY_TYPE PLUMBING
J 0
(-6450 2650);
DISPLAY 0.574468 (-6450 2650);
PAINT GREEN (-6450 2650);
DISPLAY INVISIBLE (-6450 2650);
FORCEPROP 1 LAST HDL_TAP TRUE
J 0
(-6125 2575);
DISPLAY 0.574468 (-6125 2575);
PAINT GREEN (-6125 2575);
DISPLAY INVISIBLE (-6125 2575);
FORCEPROP 1 LAST PATH I256
J 0
(-6452 2700);
DISPLAY 0.872340 (-6452 2700);
PAINT GREEN (-6452 2700);
DISPLAY INVISIBLE (-6452 2700);
FORCEADD TAP..6
(-6450 2900);
FORCEPROP 3 LASTPIN (-6400 2900) SIG_NAME P5E_CPU1_P1_RX_DP<0>
J 0
(-6390 2910);
DISPLAY 0.659574 (-6390 2910);
PAINT MONO (-6390 2910);
DISPLAY INVISIBLE (-6390 2910);
FORCEPROP 1 LASTPIN (-6400 2900) BN 0
J 0
(-6452 2908);
DISPLAY 0.489362 (-6452 2908);
PAINT MONO (-6452 2908);
FORCEPROP 2 LAST CDS_LIB mstr_standard
J 0
(-6450 2900);
DISPLAY INVISIBLE (-6450 2900);
FORCEPROP 1 LAST BODY_TYPE PLUMBING
J 0
(-6450 2850);
DISPLAY 0.574468 (-6450 2850);
PAINT GREEN (-6450 2850);
DISPLAY INVISIBLE (-6450 2850);
FORCEPROP 1 LAST HDL_TAP TRUE
J 0
(-6125 2775);
DISPLAY 0.574468 (-6125 2775);
PAINT GREEN (-6125 2775);
DISPLAY INVISIBLE (-6125 2775);
FORCEPROP 1 LAST PATH I257
J 0
(-6452 2900);
DISPLAY 0.872340 (-6452 2900);
PAINT GREEN (-6452 2900);
DISPLAY INVISIBLE (-6452 2900);
FORCEADD TAP..6
(-6450 2800);
FORCEPROP 3 LASTPIN (-6400 2800) SIG_NAME P5E_CPU1_P1_RX_DP<1>
J 0
(-6390 2810);
DISPLAY 0.659574 (-6390 2810);
PAINT MONO (-6390 2810);
DISPLAY INVISIBLE (-6390 2810);
FORCEPROP 1 LASTPIN (-6400 2800) BN 1
J 0
(-6452 2808);
DISPLAY 0.489362 (-6452 2808);
PAINT MONO (-6452 2808);
FORCEPROP 2 LAST CDS_LIB mstr_standard
J 0
(-6450 2800);
DISPLAY INVISIBLE (-6450 2800);
FORCEPROP 1 LAST BODY_TYPE PLUMBING
J 0
(-6450 2750);
DISPLAY 0.574468 (-6450 2750);
PAINT GREEN (-6450 2750);
DISPLAY INVISIBLE (-6450 2750);
FORCEPROP 1 LAST HDL_TAP TRUE
J 0
(-6125 2675);
DISPLAY 0.574468 (-6125 2675);
PAINT GREEN (-6125 2675);
DISPLAY INVISIBLE (-6125 2675);
FORCEPROP 1 LAST PATH I258
J 0
(-6452 2800);
DISPLAY 0.872340 (-6452 2800);
PAINT GREEN (-6452 2800);
DISPLAY INVISIBLE (-6452 2800);
FORCEADD TAP..6
(-6600 2850);
FORCEPROP 3 LASTPIN (-6550 2850) SIG_NAME P5E_CPU1_P1_RX_DN<0>
J 0
(-6540 2860);
DISPLAY 0.659574 (-6540 2860);
PAINT MONO (-6540 2860);
DISPLAY INVISIBLE (-6540 2860);
FORCEPROP 1 LASTPIN (-6550 2850) BN 0
J 0
(-6602 2858);
DISPLAY 0.489362 (-6602 2858);
PAINT MONO (-6602 2858);
FORCEPROP 2 LAST CDS_LIB mstr_standard
J 0
(-6600 2850);
DISPLAY INVISIBLE (-6600 2850);
FORCEPROP 1 LAST BODY_TYPE PLUMBING
J 0
(-6600 2800);
DISPLAY 0.574468 (-6600 2800);
PAINT GREEN (-6600 2800);
DISPLAY INVISIBLE (-6600 2800);
FORCEPROP 1 LAST HDL_TAP TRUE
J 0
(-6275 2725);
DISPLAY 0.574468 (-6275 2725);
PAINT GREEN (-6275 2725);
DISPLAY INVISIBLE (-6275 2725);
FORCEPROP 1 LAST PATH I259
J 0
(-6602 2850);
DISPLAY 0.872340 (-6602 2850);
PAINT GREEN (-6602 2850);
DISPLAY INVISIBLE (-6602 2850);
FORCEADD TAP..6
(-6600 2750);
FORCEPROP 3 LASTPIN (-6550 2750) SIG_NAME P5E_CPU1_P1_RX_DN<1>
J 0
(-6540 2760);
DISPLAY 0.659574 (-6540 2760);
PAINT MONO (-6540 2760);
DISPLAY INVISIBLE (-6540 2760);
FORCEPROP 1 LASTPIN (-6550 2750) BN 1
J 0
(-6602 2758);
DISPLAY 0.489362 (-6602 2758);
PAINT MONO (-6602 2758);
FORCEPROP 2 LAST CDS_LIB mstr_standard
J 0
(-6600 2750);
DISPLAY INVISIBLE (-6600 2750);
FORCEPROP 1 LAST BODY_TYPE PLUMBING
J 0
(-6600 2700);
DISPLAY 0.574468 (-6600 2700);
PAINT GREEN (-6600 2700);
DISPLAY INVISIBLE (-6600 2700);
FORCEPROP 1 LAST HDL_TAP TRUE
J 0
(-6275 2625);
DISPLAY 0.574468 (-6275 2625);
PAINT GREEN (-6275 2625);
DISPLAY INVISIBLE (-6275 2625);
FORCEPROP 1 LAST PATH I260
J 0
(-6602 2750);
DISPLAY 0.872340 (-6602 2750);
PAINT GREEN (-6602 2750);
DISPLAY INVISIBLE (-6602 2750);
FORCEADD TAP..6
(-6600 2650);
FORCEPROP 3 LASTPIN (-6550 2650) SIG_NAME P5E_CPU1_P1_RX_DN<2>
J 0
(-6540 2660);
DISPLAY 0.659574 (-6540 2660);
PAINT MONO (-6540 2660);
DISPLAY INVISIBLE (-6540 2660);
FORCEPROP 1 LASTPIN (-6550 2650) BN 2
J 0
(-6602 2658);
DISPLAY 0.489362 (-6602 2658);
PAINT MONO (-6602 2658);
FORCEPROP 2 LAST CDS_LIB standard
J 0
(-6600 2650);
DISPLAY INVISIBLE (-6600 2650);
FORCEPROP 1 LAST BODY_TYPE PLUMBING
J 0
(-6600 2600);
DISPLAY 0.574468 (-6600 2600);
PAINT GREEN (-6600 2600);
DISPLAY INVISIBLE (-6600 2600);
FORCEPROP 1 LAST HDL_TAP TRUE
J 0
(-6275 2525);
DISPLAY 0.574468 (-6275 2525);
PAINT GREEN (-6275 2525);
DISPLAY INVISIBLE (-6275 2525);
FORCEPROP 1 LAST PATH I261
J 0
(-6602 2650);
DISPLAY 0.872340 (-6602 2650);
PAINT GREEN (-6602 2650);
DISPLAY INVISIBLE (-6602 2650);
FORCEADD TAP..6
(-6450 2100);
FORCEPROP 3 LASTPIN (-6400 2100) SIG_NAME P5E_CPU1_P1_RX_DP<8>
J 0
(-6390 2110);
DISPLAY 0.659574 (-6390 2110);
PAINT MONO (-6390 2110);
DISPLAY INVISIBLE (-6390 2110);
FORCEPROP 1 LASTPIN (-6400 2100) BN 8
J 0
(-6452 2108);
DISPLAY 0.489362 (-6452 2108);
PAINT MONO (-6452 2108);
FORCEPROP 2 LAST CDS_LIB standard
J 0
(-6450 2100);
DISPLAY INVISIBLE (-6450 2100);
FORCEPROP 1 LAST BODY_TYPE PLUMBING
J 0
(-6450 2050);
DISPLAY 0.574468 (-6450 2050);
PAINT GREEN (-6450 2050);
DISPLAY INVISIBLE (-6450 2050);
FORCEPROP 1 LAST HDL_TAP TRUE
J 0
(-6125 1975);
DISPLAY 0.574468 (-6125 1975);
PAINT GREEN (-6125 1975);
DISPLAY INVISIBLE (-6125 1975);
FORCEPROP 1 LAST PATH I262
J 0
(-6452 2100);
DISPLAY 0.872340 (-6452 2100);
PAINT GREEN (-6452 2100);
DISPLAY INVISIBLE (-6452 2100);
FORCEADD TAP..6
(-6450 2200);
FORCEPROP 3 LASTPIN (-6400 2200) SIG_NAME P5E_CPU1_P1_RX_DP<7>
J 0
(-6390 2210);
DISPLAY 0.659574 (-6390 2210);
PAINT MONO (-6390 2210);
DISPLAY INVISIBLE (-6390 2210);
FORCEPROP 1 LASTPIN (-6400 2200) BN 7
J 0
(-6452 2208);
DISPLAY 0.489362 (-6452 2208);
PAINT MONO (-6452 2208);
FORCEPROP 2 LAST CDS_LIB standard
J 0
(-6450 2200);
DISPLAY INVISIBLE (-6450 2200);
FORCEPROP 1 LAST BODY_TYPE PLUMBING
J 0
(-6450 2150);
DISPLAY 0.574468 (-6450 2150);
PAINT GREEN (-6450 2150);
DISPLAY INVISIBLE (-6450 2150);
FORCEPROP 1 LAST HDL_TAP TRUE
J 0
(-6125 2075);
DISPLAY 0.574468 (-6125 2075);
PAINT GREEN (-6125 2075);
DISPLAY INVISIBLE (-6125 2075);
FORCEPROP 1 LAST PATH I263
J 0
(-6452 2200);
DISPLAY 0.872340 (-6452 2200);
PAINT GREEN (-6452 2200);
DISPLAY INVISIBLE (-6452 2200);
FORCEADD TAP..6
(-6450 2300);
FORCEPROP 3 LASTPIN (-6400 2300) SIG_NAME P5E_CPU1_P1_RX_DP<6>
J 0
(-6390 2310);
DISPLAY 0.659574 (-6390 2310);
PAINT MONO (-6390 2310);
DISPLAY INVISIBLE (-6390 2310);
FORCEPROP 1 LASTPIN (-6400 2300) BN 6
J 0
(-6452 2308);
DISPLAY 0.489362 (-6452 2308);
PAINT MONO (-6452 2308);
FORCEPROP 2 LAST CDS_LIB standard
J 0
(-6450 2300);
DISPLAY INVISIBLE (-6450 2300);
FORCEPROP 1 LAST BODY_TYPE PLUMBING
J 0
(-6450 2250);
DISPLAY 0.574468 (-6450 2250);
PAINT GREEN (-6450 2250);
DISPLAY INVISIBLE (-6450 2250);
FORCEPROP 1 LAST HDL_TAP TRUE
J 0
(-6125 2175);
DISPLAY 0.574468 (-6125 2175);
PAINT GREEN (-6125 2175);
DISPLAY INVISIBLE (-6125 2175);
FORCEPROP 1 LAST PATH I264
J 0
(-6452 2300);
DISPLAY 0.872340 (-6452 2300);
PAINT GREEN (-6452 2300);
DISPLAY INVISIBLE (-6452 2300);
FORCEADD TAP..6
(-6450 2500);
FORCEPROP 3 LASTPIN (-6400 2500) SIG_NAME P5E_CPU1_P1_RX_DP<4>
J 0
(-6390 2510);
DISPLAY 0.659574 (-6390 2510);
PAINT MONO (-6390 2510);
DISPLAY INVISIBLE (-6390 2510);
FORCEPROP 1 LASTPIN (-6400 2500) BN 4
J 0
(-6452 2508);
DISPLAY 0.489362 (-6452 2508);
PAINT MONO (-6452 2508);
FORCEPROP 2 LAST CDS_LIB standard
J 0
(-6450 2500);
DISPLAY INVISIBLE (-6450 2500);
FORCEPROP 1 LAST BODY_TYPE PLUMBING
J 0
(-6450 2450);
DISPLAY 0.574468 (-6450 2450);
PAINT GREEN (-6450 2450);
DISPLAY INVISIBLE (-6450 2450);
FORCEPROP 1 LAST HDL_TAP TRUE
J 0
(-6125 2375);
DISPLAY 0.574468 (-6125 2375);
PAINT GREEN (-6125 2375);
DISPLAY INVISIBLE (-6125 2375);
FORCEPROP 1 LAST PATH I265
J 0
(-6452 2500);
DISPLAY 0.872340 (-6452 2500);
PAINT GREEN (-6452 2500);
DISPLAY INVISIBLE (-6452 2500);
FORCEADD TAP..6
(-6450 2400);
FORCEPROP 3 LASTPIN (-6400 2400) SIG_NAME P5E_CPU1_P1_RX_DP<5>
J 0
(-6390 2410);
DISPLAY 0.659574 (-6390 2410);
PAINT MONO (-6390 2410);
DISPLAY INVISIBLE (-6390 2410);
FORCEPROP 1 LASTPIN (-6400 2400) BN 5
J 0
(-6452 2408);
DISPLAY 0.489362 (-6452 2408);
PAINT MONO (-6452 2408);
FORCEPROP 2 LAST CDS_LIB standard
J 0
(-6450 2400);
DISPLAY INVISIBLE (-6450 2400);
FORCEPROP 1 LAST BODY_TYPE PLUMBING
J 0
(-6450 2350);
DISPLAY 0.574468 (-6450 2350);
PAINT GREEN (-6450 2350);
DISPLAY INVISIBLE (-6450 2350);
FORCEPROP 1 LAST HDL_TAP TRUE
J 0
(-6125 2275);
DISPLAY 0.574468 (-6125 2275);
PAINT GREEN (-6125 2275);
DISPLAY INVISIBLE (-6125 2275);
FORCEPROP 1 LAST PATH I266
J 0
(-6452 2400);
DISPLAY 0.872340 (-6452 2400);
PAINT GREEN (-6452 2400);
DISPLAY INVISIBLE (-6452 2400);
FORCEADD TAP..6
(-6600 2550);
FORCEPROP 3 LASTPIN (-6550 2550) SIG_NAME P5E_CPU1_P1_RX_DN<3>
J 0
(-6540 2560);
DISPLAY 0.659574 (-6540 2560);
PAINT MONO (-6540 2560);
DISPLAY INVISIBLE (-6540 2560);
FORCEPROP 1 LASTPIN (-6550 2550) BN 3
J 0
(-6602 2558);
DISPLAY 0.489362 (-6602 2558);
PAINT MONO (-6602 2558);
FORCEPROP 2 LAST CDS_LIB standard
J 0
(-6600 2550);
DISPLAY INVISIBLE (-6600 2550);
FORCEPROP 1 LAST BODY_TYPE PLUMBING
J 0
(-6600 2500);
DISPLAY 0.574468 (-6600 2500);
PAINT GREEN (-6600 2500);
DISPLAY INVISIBLE (-6600 2500);
FORCEPROP 1 LAST HDL_TAP TRUE
J 0
(-6275 2425);
DISPLAY 0.574468 (-6275 2425);
PAINT GREEN (-6275 2425);
DISPLAY INVISIBLE (-6275 2425);
FORCEPROP 1 LAST PATH I267
J 0
(-6602 2550);
DISPLAY 0.872340 (-6602 2550);
PAINT GREEN (-6602 2550);
DISPLAY INVISIBLE (-6602 2550);
FORCEADD TAP..6
(-6600 2450);
FORCEPROP 3 LASTPIN (-6550 2450) SIG_NAME P5E_CPU1_P1_RX_DN<4>
J 0
(-6540 2460);
DISPLAY 0.659574 (-6540 2460);
PAINT MONO (-6540 2460);
DISPLAY INVISIBLE (-6540 2460);
FORCEPROP 1 LASTPIN (-6550 2450) BN 4
J 0
(-6602 2458);
DISPLAY 0.489362 (-6602 2458);
PAINT MONO (-6602 2458);
FORCEPROP 2 LAST CDS_LIB standard
J 0
(-6600 2450);
DISPLAY INVISIBLE (-6600 2450);
FORCEPROP 1 LAST BODY_TYPE PLUMBING
J 0
(-6600 2400);
DISPLAY 0.574468 (-6600 2400);
PAINT GREEN (-6600 2400);
DISPLAY INVISIBLE (-6600 2400);
FORCEPROP 1 LAST HDL_TAP TRUE
J 0
(-6275 2325);
DISPLAY 0.574468 (-6275 2325);
PAINT GREEN (-6275 2325);
DISPLAY INVISIBLE (-6275 2325);
FORCEPROP 1 LAST PATH I268
J 0
(-6602 2450);
DISPLAY 0.872340 (-6602 2450);
PAINT GREEN (-6602 2450);
DISPLAY INVISIBLE (-6602 2450);
FORCEADD TAP..6
(-6600 2350);
FORCEPROP 3 LASTPIN (-6550 2350) SIG_NAME P5E_CPU1_P1_RX_DN<5>
J 0
(-6540 2360);
DISPLAY 0.659574 (-6540 2360);
PAINT MONO (-6540 2360);
DISPLAY INVISIBLE (-6540 2360);
FORCEPROP 1 LASTPIN (-6550 2350) BN 5
J 0
(-6602 2358);
DISPLAY 0.489362 (-6602 2358);
PAINT MONO (-6602 2358);
FORCEPROP 2 LAST CDS_LIB standard
J 0
(-6600 2350);
DISPLAY INVISIBLE (-6600 2350);
FORCEPROP 1 LAST BODY_TYPE PLUMBING
J 0
(-6600 2300);
DISPLAY 0.574468 (-6600 2300);
PAINT GREEN (-6600 2300);
DISPLAY INVISIBLE (-6600 2300);
FORCEPROP 1 LAST HDL_TAP TRUE
J 0
(-6275 2225);
DISPLAY 0.574468 (-6275 2225);
PAINT GREEN (-6275 2225);
DISPLAY INVISIBLE (-6275 2225);
FORCEPROP 1 LAST PATH I269
J 0
(-6602 2350);
DISPLAY 0.872340 (-6602 2350);
PAINT GREEN (-6602 2350);
DISPLAY INVISIBLE (-6602 2350);
FORCEADD TAP..6
(-6600 2150);
FORCEPROP 3 LASTPIN (-6550 2150) SIG_NAME P5E_CPU1_P1_RX_DN<7>
J 0
(-6540 2160);
DISPLAY 0.659574 (-6540 2160);
PAINT MONO (-6540 2160);
DISPLAY INVISIBLE (-6540 2160);
FORCEPROP 1 LASTPIN (-6550 2150) BN 7
J 0
(-6602 2158);
DISPLAY 0.489362 (-6602 2158);
PAINT MONO (-6602 2158);
FORCEPROP 2 LAST CDS_LIB standard
J 0
(-6600 2150);
DISPLAY INVISIBLE (-6600 2150);
FORCEPROP 1 LAST BODY_TYPE PLUMBING
J 0
(-6600 2100);
DISPLAY 0.574468 (-6600 2100);
PAINT GREEN (-6600 2100);
DISPLAY INVISIBLE (-6600 2100);
FORCEPROP 1 LAST HDL_TAP TRUE
J 0
(-6275 2025);
DISPLAY 0.574468 (-6275 2025);
PAINT GREEN (-6275 2025);
DISPLAY INVISIBLE (-6275 2025);
FORCEPROP 1 LAST PATH I270
J 0
(-6602 2150);
DISPLAY 0.872340 (-6602 2150);
PAINT GREEN (-6602 2150);
DISPLAY INVISIBLE (-6602 2150);
FORCEADD TAP..6
(-6600 2250);
FORCEPROP 3 LASTPIN (-6550 2250) SIG_NAME P5E_CPU1_P1_RX_DN<6>
J 0
(-6540 2260);
DISPLAY 0.659574 (-6540 2260);
PAINT MONO (-6540 2260);
DISPLAY INVISIBLE (-6540 2260);
FORCEPROP 1 LASTPIN (-6550 2250) BN 6
J 0
(-6602 2258);
DISPLAY 0.489362 (-6602 2258);
PAINT MONO (-6602 2258);
FORCEPROP 2 LAST CDS_LIB standard
J 0
(-6600 2250);
DISPLAY INVISIBLE (-6600 2250);
FORCEPROP 1 LAST BODY_TYPE PLUMBING
J 0
(-6600 2200);
DISPLAY 0.574468 (-6600 2200);
PAINT GREEN (-6600 2200);
DISPLAY INVISIBLE (-6600 2200);
FORCEPROP 1 LAST HDL_TAP TRUE
J 0
(-6275 2125);
DISPLAY 0.574468 (-6275 2125);
PAINT GREEN (-6275 2125);
DISPLAY INVISIBLE (-6275 2125);
FORCEPROP 1 LAST PATH I271
J 0
(-6602 2250);
DISPLAY 0.872340 (-6602 2250);
PAINT GREEN (-6602 2250);
DISPLAY INVISIBLE (-6602 2250);
FORCEADD TAP..6
(-6600 2050);
FORCEPROP 3 LASTPIN (-6550 2050) SIG_NAME P5E_CPU1_P1_RX_DN<8>
J 0
(-6540 2060);
DISPLAY 0.659574 (-6540 2060);
PAINT MONO (-6540 2060);
DISPLAY INVISIBLE (-6540 2060);
FORCEPROP 1 LASTPIN (-6550 2050) BN 8
J 0
(-6602 2058);
DISPLAY 0.489362 (-6602 2058);
PAINT MONO (-6602 2058);
FORCEPROP 2 LAST CDS_LIB standard
J 0
(-6600 2050);
DISPLAY INVISIBLE (-6600 2050);
FORCEPROP 1 LAST BODY_TYPE PLUMBING
J 0
(-6600 2000);
DISPLAY 0.574468 (-6600 2000);
PAINT GREEN (-6600 2000);
DISPLAY INVISIBLE (-6600 2000);
FORCEPROP 1 LAST HDL_TAP TRUE
J 0
(-6275 1925);
DISPLAY 0.574468 (-6275 1925);
PAINT GREEN (-6275 1925);
DISPLAY INVISIBLE (-6275 1925);
FORCEPROP 1 LAST PATH I272
J 0
(-6602 2050);
DISPLAY 0.872340 (-6602 2050);
PAINT GREEN (-6602 2050);
DISPLAY INVISIBLE (-6602 2050);
FORCEADD OFFPAGE..1
(-7625 3125);
FORCEPROP 2 LAST $XR0 329 
J 0
(-7877 3125);
DISPLAY 0.638298 (-7877 3125);
PAINT MONO (-7877 3125);
FORCEPROP 2 LAST CDS_LIB standard
J 0
(-7625 3125);
DISPLAY INVISIBLE (-7625 3125);
FORCEPROP 1 LAST OFFPAGE TRUE
J 0
(-7300 3000);
DISPLAY 0.872340 (-7300 3000);
PAINT GREEN (-7300 3000);
DISPLAY INVISIBLE (-7300 3000);
FORCEPROP 1 LAST COMMENT_BODY TRUE
J 0
(-7500 3025);
DISPLAY 0.872340 (-7500 3025);
PAINT GREEN (-7500 3025);
DISPLAY INVISIBLE (-7500 3025);
FORCEPROP 2 LAST PATH I273
J 0
(-7575 3200);
DISPLAY 1.021277 (-7575 3200);
DISPLAY INVISIBLE (-7575 3200);
FORCEADD OFFPAGE..1
(-7625 3075);
FORCEPROP 2 LAST $XR0 329 
J 0
(-7877 3075);
DISPLAY 0.638298 (-7877 3075);
PAINT MONO (-7877 3075);
FORCEPROP 2 LAST CDS_LIB standard
J 0
(-7625 3075);
DISPLAY INVISIBLE (-7625 3075);
FORCEPROP 1 LAST OFFPAGE TRUE
J 0
(-7300 2950);
DISPLAY 0.872340 (-7300 2950);
PAINT GREEN (-7300 2950);
DISPLAY INVISIBLE (-7300 2950);
FORCEPROP 1 LAST COMMENT_BODY TRUE
J 0
(-7500 2975);
DISPLAY 0.872340 (-7500 2975);
PAINT GREEN (-7500 2975);
DISPLAY INVISIBLE (-7500 2975);
FORCEPROP 2 LAST PATH I274
J 0
(-7575 3150);
DISPLAY 1.021277 (-7575 3150);
DISPLAY INVISIBLE (-7575 3150);
FORCEADD TAP..6
(-6450 1800);
FORCEPROP 3 LASTPIN (-6400 1800) SIG_NAME P5E_CPU1_P1_RX_DP<11>
J 0
(-6390 1810);
DISPLAY 0.659574 (-6390 1810);
PAINT MONO (-6390 1810);
DISPLAY INVISIBLE (-6390 1810);
FORCEPROP 1 LASTPIN (-6400 1800) BN 11
J 0
(-6452 1808);
DISPLAY 0.489362 (-6452 1808);
PAINT MONO (-6452 1808);
FORCEPROP 2 LAST CDS_LIB standard
J 0
(-6450 1800);
DISPLAY INVISIBLE (-6450 1800);
FORCEPROP 1 LAST BODY_TYPE PLUMBING
J 0
(-6450 1750);
DISPLAY 0.574468 (-6450 1750);
PAINT GREEN (-6450 1750);
DISPLAY INVISIBLE (-6450 1750);
FORCEPROP 1 LAST HDL_TAP TRUE
J 0
(-6125 1675);
DISPLAY 0.574468 (-6125 1675);
PAINT GREEN (-6125 1675);
DISPLAY INVISIBLE (-6125 1675);
FORCEPROP 1 LAST PATH I275
J 0
(-6452 1800);
DISPLAY 0.872340 (-6452 1800);
PAINT GREEN (-6452 1800);
DISPLAY INVISIBLE (-6452 1800);
FORCEADD TAP..6
(-6450 1900);
FORCEPROP 3 LASTPIN (-6400 1900) SIG_NAME P5E_CPU1_P1_RX_DP<10>
J 0
(-6390 1910);
DISPLAY 0.659574 (-6390 1910);
PAINT MONO (-6390 1910);
DISPLAY INVISIBLE (-6390 1910);
FORCEPROP 1 LASTPIN (-6400 1900) BN 10
J 0
(-6452 1908);
DISPLAY 0.489362 (-6452 1908);
PAINT MONO (-6452 1908);
FORCEPROP 2 LAST CDS_LIB standard
J 0
(-6450 1900);
DISPLAY INVISIBLE (-6450 1900);
FORCEPROP 1 LAST BODY_TYPE PLUMBING
J 0
(-6450 1850);
DISPLAY 0.574468 (-6450 1850);
PAINT GREEN (-6450 1850);
DISPLAY INVISIBLE (-6450 1850);
FORCEPROP 1 LAST HDL_TAP TRUE
J 0
(-6125 1775);
DISPLAY 0.574468 (-6125 1775);
PAINT GREEN (-6125 1775);
DISPLAY INVISIBLE (-6125 1775);
FORCEPROP 1 LAST PATH I276
J 0
(-6452 1900);
DISPLAY 0.872340 (-6452 1900);
PAINT GREEN (-6452 1900);
DISPLAY INVISIBLE (-6452 1900);
FORCEADD TAP..6
(-6450 2000);
FORCEPROP 3 LASTPIN (-6400 2000) SIG_NAME P5E_CPU1_P1_RX_DP<9>
J 0
(-6390 2010);
DISPLAY 0.659574 (-6390 2010);
PAINT MONO (-6390 2010);
DISPLAY INVISIBLE (-6390 2010);
FORCEPROP 1 LASTPIN (-6400 2000) BN 9
J 0
(-6452 2008);
DISPLAY 0.489362 (-6452 2008);
PAINT MONO (-6452 2008);
FORCEPROP 2 LAST CDS_LIB standard
J 0
(-6450 2000);
DISPLAY INVISIBLE (-6450 2000);
FORCEPROP 1 LAST BODY_TYPE PLUMBING
J 0
(-6450 1950);
DISPLAY 0.574468 (-6450 1950);
PAINT GREEN (-6450 1950);
DISPLAY INVISIBLE (-6450 1950);
FORCEPROP 1 LAST HDL_TAP TRUE
J 0
(-6125 1875);
DISPLAY 0.574468 (-6125 1875);
PAINT GREEN (-6125 1875);
DISPLAY INVISIBLE (-6125 1875);
FORCEPROP 1 LAST PATH I277
J 0
(-6452 2000);
DISPLAY 0.872340 (-6452 2000);
PAINT GREEN (-6452 2000);
DISPLAY INVISIBLE (-6452 2000);
FORCEADD TAP..6
(-6450 1700);
FORCEPROP 3 LASTPIN (-6400 1700) SIG_NAME P5E_CPU1_P1_RX_DP<12>
J 0
(-6390 1710);
DISPLAY 0.659574 (-6390 1710);
PAINT MONO (-6390 1710);
DISPLAY INVISIBLE (-6390 1710);
FORCEPROP 1 LASTPIN (-6400 1700) BN 12
J 0
(-6452 1708);
DISPLAY 0.489362 (-6452 1708);
PAINT MONO (-6452 1708);
FORCEPROP 2 LAST CDS_LIB standard
J 0
(-6450 1700);
DISPLAY INVISIBLE (-6450 1700);
FORCEPROP 1 LAST BODY_TYPE PLUMBING
J 0
(-6450 1650);
DISPLAY 0.574468 (-6450 1650);
PAINT GREEN (-6450 1650);
DISPLAY INVISIBLE (-6450 1650);
FORCEPROP 1 LAST HDL_TAP TRUE
J 0
(-6125 1575);
DISPLAY 0.574468 (-6125 1575);
PAINT GREEN (-6125 1575);
DISPLAY INVISIBLE (-6125 1575);
FORCEPROP 1 LAST PATH I278
J 0
(-6452 1700);
DISPLAY 0.872340 (-6452 1700);
PAINT GREEN (-6452 1700);
DISPLAY INVISIBLE (-6452 1700);
FORCEADD TAP..6
(-6450 1600);
FORCEPROP 3 LASTPIN (-6400 1600) SIG_NAME P5E_CPU1_P1_RX_DP<13>
J 0
(-6390 1610);
DISPLAY 0.659574 (-6390 1610);
PAINT MONO (-6390 1610);
DISPLAY INVISIBLE (-6390 1610);
FORCEPROP 1 LASTPIN (-6400 1600) BN 13
J 0
(-6452 1608);
DISPLAY 0.489362 (-6452 1608);
PAINT MONO (-6452 1608);
FORCEPROP 2 LAST CDS_LIB standard
J 0
(-6450 1600);
DISPLAY INVISIBLE (-6450 1600);
FORCEPROP 1 LAST BODY_TYPE PLUMBING
J 0
(-6450 1550);
DISPLAY 0.574468 (-6450 1550);
PAINT GREEN (-6450 1550);
DISPLAY INVISIBLE (-6450 1550);
FORCEPROP 1 LAST HDL_TAP TRUE
J 0
(-6125 1475);
DISPLAY 0.574468 (-6125 1475);
PAINT GREEN (-6125 1475);
DISPLAY INVISIBLE (-6125 1475);
FORCEPROP 1 LAST PATH I279
J 0
(-6452 1600);
DISPLAY 0.872340 (-6452 1600);
PAINT GREEN (-6452 1600);
DISPLAY INVISIBLE (-6452 1600);
FORCEADD TAP..6
(-6600 1950);
FORCEPROP 3 LASTPIN (-6550 1950) SIG_NAME P5E_CPU1_P1_RX_DN<9>
J 0
(-6540 1960);
DISPLAY 0.659574 (-6540 1960);
PAINT MONO (-6540 1960);
DISPLAY INVISIBLE (-6540 1960);
FORCEPROP 1 LASTPIN (-6550 1950) BN 9
J 0
(-6602 1958);
DISPLAY 0.489362 (-6602 1958);
PAINT MONO (-6602 1958);
FORCEPROP 2 LAST CDS_LIB standard
J 0
(-6600 1950);
DISPLAY INVISIBLE (-6600 1950);
FORCEPROP 1 LAST BODY_TYPE PLUMBING
J 0
(-6600 1900);
DISPLAY 0.574468 (-6600 1900);
PAINT GREEN (-6600 1900);
DISPLAY INVISIBLE (-6600 1900);
FORCEPROP 1 LAST HDL_TAP TRUE
J 0
(-6275 1825);
DISPLAY 0.574468 (-6275 1825);
PAINT GREEN (-6275 1825);
DISPLAY INVISIBLE (-6275 1825);
FORCEPROP 1 LAST PATH I280
J 0
(-6602 1950);
DISPLAY 0.872340 (-6602 1950);
PAINT GREEN (-6602 1950);
DISPLAY INVISIBLE (-6602 1950);
FORCEADD TAP..6
(-6600 1850);
FORCEPROP 3 LASTPIN (-6550 1850) SIG_NAME P5E_CPU1_P1_RX_DN<10>
J 0
(-6540 1860);
DISPLAY 0.659574 (-6540 1860);
PAINT MONO (-6540 1860);
DISPLAY INVISIBLE (-6540 1860);
FORCEPROP 1 LASTPIN (-6550 1850) BN 10
J 0
(-6602 1858);
DISPLAY 0.489362 (-6602 1858);
PAINT MONO (-6602 1858);
FORCEPROP 2 LAST CDS_LIB standard
J 0
(-6600 1850);
DISPLAY INVISIBLE (-6600 1850);
FORCEPROP 1 LAST BODY_TYPE PLUMBING
J 0
(-6600 1800);
DISPLAY 0.574468 (-6600 1800);
PAINT GREEN (-6600 1800);
DISPLAY INVISIBLE (-6600 1800);
FORCEPROP 1 LAST HDL_TAP TRUE
J 0
(-6275 1725);
DISPLAY 0.574468 (-6275 1725);
PAINT GREEN (-6275 1725);
DISPLAY INVISIBLE (-6275 1725);
FORCEPROP 1 LAST PATH I281
J 0
(-6602 1850);
DISPLAY 0.872340 (-6602 1850);
PAINT GREEN (-6602 1850);
DISPLAY INVISIBLE (-6602 1850);
FORCEADD TAP..6
(-6600 1750);
FORCEPROP 3 LASTPIN (-6550 1750) SIG_NAME P5E_CPU1_P1_RX_DN<11>
J 0
(-6540 1760);
DISPLAY 0.659574 (-6540 1760);
PAINT MONO (-6540 1760);
DISPLAY INVISIBLE (-6540 1760);
FORCEPROP 1 LASTPIN (-6550 1750) BN 11
J 0
(-6602 1758);
DISPLAY 0.489362 (-6602 1758);
PAINT MONO (-6602 1758);
FORCEPROP 2 LAST CDS_LIB standard
J 0
(-6600 1750);
DISPLAY INVISIBLE (-6600 1750);
FORCEPROP 1 LAST BODY_TYPE PLUMBING
J 0
(-6600 1700);
DISPLAY 0.574468 (-6600 1700);
PAINT GREEN (-6600 1700);
DISPLAY INVISIBLE (-6600 1700);
FORCEPROP 1 LAST HDL_TAP TRUE
J 0
(-6275 1625);
DISPLAY 0.574468 (-6275 1625);
PAINT GREEN (-6275 1625);
DISPLAY INVISIBLE (-6275 1625);
FORCEPROP 1 LAST PATH I282
J 0
(-6602 1750);
DISPLAY 0.872340 (-6602 1750);
PAINT GREEN (-6602 1750);
DISPLAY INVISIBLE (-6602 1750);
FORCEADD TAP..6
(-6600 1650);
FORCEPROP 3 LASTPIN (-6550 1650) SIG_NAME P5E_CPU1_P1_RX_DN<12>
J 0
(-6540 1660);
DISPLAY 0.659574 (-6540 1660);
PAINT MONO (-6540 1660);
DISPLAY INVISIBLE (-6540 1660);
FORCEPROP 1 LASTPIN (-6550 1650) BN 12
J 0
(-6602 1658);
DISPLAY 0.489362 (-6602 1658);
PAINT MONO (-6602 1658);
FORCEPROP 2 LAST CDS_LIB standard
J 0
(-6600 1650);
DISPLAY INVISIBLE (-6600 1650);
FORCEPROP 1 LAST BODY_TYPE PLUMBING
J 0
(-6600 1600);
DISPLAY 0.574468 (-6600 1600);
PAINT GREEN (-6600 1600);
DISPLAY INVISIBLE (-6600 1600);
FORCEPROP 1 LAST HDL_TAP TRUE
J 0
(-6275 1525);
DISPLAY 0.574468 (-6275 1525);
PAINT GREEN (-6275 1525);
DISPLAY INVISIBLE (-6275 1525);
FORCEPROP 1 LAST PATH I283
J 0
(-6602 1650);
DISPLAY 0.872340 (-6602 1650);
PAINT GREEN (-6602 1650);
DISPLAY INVISIBLE (-6602 1650);
FORCEADD TAP..6
(-6600 1550);
FORCEPROP 3 LASTPIN (-6550 1550) SIG_NAME P5E_CPU1_P1_RX_DN<13>
J 0
(-6540 1560);
DISPLAY 0.659574 (-6540 1560);
PAINT MONO (-6540 1560);
DISPLAY INVISIBLE (-6540 1560);
FORCEPROP 1 LASTPIN (-6550 1550) BN 13
J 0
(-6602 1558);
DISPLAY 0.489362 (-6602 1558);
PAINT MONO (-6602 1558);
FORCEPROP 2 LAST CDS_LIB standard
J 0
(-6600 1550);
DISPLAY INVISIBLE (-6600 1550);
FORCEPROP 1 LAST BODY_TYPE PLUMBING
J 0
(-6600 1500);
DISPLAY 0.574468 (-6600 1500);
PAINT GREEN (-6600 1500);
DISPLAY INVISIBLE (-6600 1500);
FORCEPROP 1 LAST HDL_TAP TRUE
J 0
(-6275 1425);
DISPLAY 0.574468 (-6275 1425);
PAINT GREEN (-6275 1425);
DISPLAY INVISIBLE (-6275 1425);
FORCEPROP 1 LAST PATH I284
J 0
(-6602 1550);
DISPLAY 0.872340 (-6602 1550);
PAINT GREEN (-6602 1550);
DISPLAY INVISIBLE (-6602 1550);
FORCEADD TAP..6
(-6450 1500);
FORCEPROP 3 LASTPIN (-6400 1500) SIG_NAME P5E_CPU1_P1_RX_DP<14>
J 0
(-6390 1510);
DISPLAY 0.659574 (-6390 1510);
PAINT MONO (-6390 1510);
DISPLAY INVISIBLE (-6390 1510);
FORCEPROP 1 LASTPIN (-6400 1500) BN 14
J 0
(-6452 1508);
DISPLAY 0.489362 (-6452 1508);
PAINT MONO (-6452 1508);
FORCEPROP 2 LAST CDS_LIB standard
J 0
(-6450 1500);
DISPLAY INVISIBLE (-6450 1500);
FORCEPROP 1 LAST BODY_TYPE PLUMBING
J 0
(-6450 1450);
DISPLAY 0.574468 (-6450 1450);
PAINT GREEN (-6450 1450);
DISPLAY INVISIBLE (-6450 1450);
FORCEPROP 1 LAST HDL_TAP TRUE
J 0
(-6125 1375);
DISPLAY 0.574468 (-6125 1375);
PAINT GREEN (-6125 1375);
DISPLAY INVISIBLE (-6125 1375);
FORCEPROP 1 LAST PATH I285
J 0
(-6452 1500);
DISPLAY 0.872340 (-6452 1500);
PAINT GREEN (-6452 1500);
DISPLAY INVISIBLE (-6452 1500);
FORCEADD TAP..6
(-6450 1400);
FORCEPROP 3 LASTPIN (-6400 1400) SIG_NAME P5E_CPU1_P1_RX_DP<15>
J 0
(-6390 1410);
DISPLAY 0.659574 (-6390 1410);
PAINT MONO (-6390 1410);
DISPLAY INVISIBLE (-6390 1410);
FORCEPROP 1 LASTPIN (-6400 1400) BN 15
J 0
(-6452 1408);
DISPLAY 0.489362 (-6452 1408);
PAINT MONO (-6452 1408);
FORCEPROP 2 LAST CDS_LIB standard
J 0
(-6450 1400);
DISPLAY INVISIBLE (-6450 1400);
FORCEPROP 1 LAST BODY_TYPE PLUMBING
J 0
(-6450 1350);
DISPLAY 0.574468 (-6450 1350);
PAINT GREEN (-6450 1350);
DISPLAY INVISIBLE (-6450 1350);
FORCEPROP 1 LAST HDL_TAP TRUE
J 0
(-6125 1275);
DISPLAY 0.574468 (-6125 1275);
PAINT GREEN (-6125 1275);
DISPLAY INVISIBLE (-6125 1275);
FORCEPROP 1 LAST PATH I286
J 0
(-6452 1400);
DISPLAY 0.872340 (-6452 1400);
PAINT GREEN (-6452 1400);
DISPLAY INVISIBLE (-6452 1400);
FORCEADD TAP..6
(-6600 1350);
FORCEPROP 3 LASTPIN (-6550 1350) SIG_NAME P5E_CPU1_P1_RX_DN<15>
J 0
(-6540 1360);
DISPLAY 0.659574 (-6540 1360);
PAINT MONO (-6540 1360);
DISPLAY INVISIBLE (-6540 1360);
FORCEPROP 1 LASTPIN (-6550 1350) BN 15
J 0
(-6602 1358);
DISPLAY 0.489362 (-6602 1358);
PAINT MONO (-6602 1358);
FORCEPROP 2 LAST CDS_LIB standard
J 0
(-6600 1350);
DISPLAY INVISIBLE (-6600 1350);
FORCEPROP 1 LAST BODY_TYPE PLUMBING
J 0
(-6600 1300);
DISPLAY 0.574468 (-6600 1300);
PAINT GREEN (-6600 1300);
DISPLAY INVISIBLE (-6600 1300);
FORCEPROP 1 LAST HDL_TAP TRUE
J 0
(-6275 1225);
DISPLAY 0.574468 (-6275 1225);
PAINT GREEN (-6275 1225);
DISPLAY INVISIBLE (-6275 1225);
FORCEPROP 1 LAST PATH I287
J 0
(-6602 1350);
DISPLAY 0.872340 (-6602 1350);
PAINT GREEN (-6602 1350);
DISPLAY INVISIBLE (-6602 1350);
FORCEADD TAP..6
(-6600 1450);
FORCEPROP 3 LASTPIN (-6550 1450) SIG_NAME P5E_CPU1_P1_RX_DN<14>
J 0
(-6540 1460);
DISPLAY 0.659574 (-6540 1460);
PAINT MONO (-6540 1460);
DISPLAY INVISIBLE (-6540 1460);
FORCEPROP 1 LASTPIN (-6550 1450) BN 14
J 0
(-6602 1458);
DISPLAY 0.489362 (-6602 1458);
PAINT MONO (-6602 1458);
FORCEPROP 2 LAST CDS_LIB standard
J 0
(-6600 1450);
DISPLAY INVISIBLE (-6600 1450);
FORCEPROP 1 LAST BODY_TYPE PLUMBING
J 0
(-6600 1400);
DISPLAY 0.574468 (-6600 1400);
PAINT GREEN (-6600 1400);
DISPLAY INVISIBLE (-6600 1400);
FORCEPROP 1 LAST HDL_TAP TRUE
J 0
(-6275 1325);
DISPLAY 0.574468 (-6275 1325);
PAINT GREEN (-6275 1325);
DISPLAY INVISIBLE (-6275 1325);
FORCEPROP 1 LAST PATH I288
J 0
(-6602 1450);
DISPLAY 0.872340 (-6602 1450);
PAINT GREEN (-6602 1450);
DISPLAY INVISIBLE (-6602 1450);
FORCEADD OFFPAGE..2
(-1825 5775);
FORCEPROP 2 LAST $XR0 65 
J 0
(-1636 5775);
DISPLAY 0.638298 (-1636 5775);
PAINT MONO (-1636 5775);
FORCEPROP 2 LAST CDS_LIB standard
J 0
(-1825 5775);
DISPLAY INVISIBLE (-1825 5775);
FORCEPROP 1 LAST OFFPAGE TRUE
J 0
(-1500 5650);
DISPLAY 0.872340 (-1500 5650);
PAINT GREEN (-1500 5650);
DISPLAY INVISIBLE (-1500 5650);
FORCEPROP 1 LAST COMMENT_BODY TRUE
J 0
(-1870 5680);
DISPLAY 0.872340 (-1870 5680);
PAINT GREEN (-1870 5680);
DISPLAY INVISIBLE (-1870 5680);
FORCEPROP 2 LAST PATH I289
J 0
(-1650 5850);
DISPLAY 1.021277 (-1650 5850);
DISPLAY INVISIBLE (-1650 5850);
FORCEADD TAP..6
R 2
(-2950 5550);
FORCEPROP 3 LASTPIN (-3000 5550) SIG_NAME P5E_CPU1_P0_TX_DP<0>
J 0
(-2990 5560);
DISPLAY 0.659574 (-2990 5560);
PAINT MONO (-2990 5560);
DISPLAY INVISIBLE (-2990 5560);
FORCEPROP 1 LASTPIN (-3000 5550) BN 0
J 2
(-2948 5558);
DISPLAY 0.489362 (-2948 5558);
PAINT MONO (-2948 5558);
FORCEPROP 2 LAST ROOM RISER1
J 0
(-3450 5600);
DISPLAY 0.829787 (-3450 5600);
PAINT RED (-3450 5600);
DISPLAY INVISIBLE (-3450 5600);
FORCEPROP 2 LAST BOM_COST IO_SLOT
J 0
(-3450 5650);
DISPLAY 0.829787 (-3450 5650);
DISPLAY INVISIBLE (-3450 5650);
FORCEPROP 2 LAST CDS_LIB mstr_standard
J 0
(-2950 5550);
DISPLAY INVISIBLE (-2950 5550);
FORCEPROP 1 LAST BODY_TYPE PLUMBING
J 2
(-2950 5500);
DISPLAY 0.702128 (-2950 5500);
PAINT GREEN (-2950 5500);
DISPLAY INVISIBLE (-2950 5500);
FORCEPROP 1 LAST HDL_TAP TRUE
J 2
(-3275 5425);
DISPLAY 0.702128 (-3275 5425);
PAINT GREEN (-3275 5425);
DISPLAY INVISIBLE (-3275 5425);
FORCEPROP 1 LAST PATH I291
J 2
(-2948 5550);
DISPLAY 0.872340 (-2948 5550);
PAINT GREEN (-2948 5550);
DISPLAY INVISIBLE (-2948 5550);
FORCEADD TAP..6
R 2
(-2950 5350);
FORCEPROP 3 LASTPIN (-3000 5350) SIG_NAME P5E_CPU1_P0_TX_DP<2>
J 0
(-2990 5360);
DISPLAY 0.659574 (-2990 5360);
PAINT MONO (-2990 5360);
DISPLAY INVISIBLE (-2990 5360);
FORCEPROP 1 LASTPIN (-3000 5350) BN 2
J 2
(-2948 5358);
DISPLAY 0.489362 (-2948 5358);
PAINT MONO (-2948 5358);
FORCEPROP 2 LAST ROOM RISER1
J 0
(-3450 5400);
DISPLAY 0.829787 (-3450 5400);
PAINT RED (-3450 5400);
DISPLAY INVISIBLE (-3450 5400);
FORCEPROP 2 LAST BOM_COST IO_SLOT
J 0
(-3450 5450);
DISPLAY 0.829787 (-3450 5450);
DISPLAY INVISIBLE (-3450 5450);
FORCEPROP 2 LAST CDS_LIB standard
J 0
(-2950 5350);
DISPLAY INVISIBLE (-2950 5350);
FORCEPROP 1 LAST BODY_TYPE PLUMBING
J 2
(-2950 5300);
DISPLAY 0.702128 (-2950 5300);
PAINT GREEN (-2950 5300);
DISPLAY INVISIBLE (-2950 5300);
FORCEPROP 1 LAST HDL_TAP TRUE
J 2
(-3275 5225);
DISPLAY 0.702128 (-3275 5225);
PAINT GREEN (-3275 5225);
DISPLAY INVISIBLE (-3275 5225);
FORCEPROP 1 LAST PATH I295
J 2
(-2948 5350);
DISPLAY 0.872340 (-2948 5350);
PAINT GREEN (-2948 5350);
DISPLAY INVISIBLE (-2948 5350);
FORCEADD TAP..6
R 2
(-2950 5450);
FORCEPROP 3 LASTPIN (-3000 5450) SIG_NAME P5E_CPU1_P0_TX_DP<1>
J 0
(-2990 5460);
DISPLAY 0.659574 (-2990 5460);
PAINT MONO (-2990 5460);
DISPLAY INVISIBLE (-2990 5460);
FORCEPROP 1 LASTPIN (-3000 5450) BN 1
J 2
(-2948 5458);
DISPLAY 0.489362 (-2948 5458);
PAINT MONO (-2948 5458);
FORCEPROP 2 LAST ROOM RISER1
J 0
(-3450 5500);
DISPLAY 0.829787 (-3450 5500);
PAINT RED (-3450 5500);
DISPLAY INVISIBLE (-3450 5500);
FORCEPROP 2 LAST BOM_COST IO_SLOT
J 0
(-3450 5550);
DISPLAY 0.829787 (-3450 5550);
DISPLAY INVISIBLE (-3450 5550);
FORCEPROP 2 LAST CDS_LIB mstr_standard
J 0
(-2950 5450);
DISPLAY INVISIBLE (-2950 5450);
FORCEPROP 1 LAST BODY_TYPE PLUMBING
J 2
(-2950 5400);
DISPLAY 0.702128 (-2950 5400);
PAINT GREEN (-2950 5400);
DISPLAY INVISIBLE (-2950 5400);
FORCEPROP 1 LAST HDL_TAP TRUE
J 2
(-3275 5325);
DISPLAY 0.702128 (-3275 5325);
PAINT GREEN (-3275 5325);
DISPLAY INVISIBLE (-3275 5325);
FORCEPROP 1 LAST PATH I296
J 2
(-2948 5450);
DISPLAY 0.872340 (-2948 5450);
PAINT GREEN (-2948 5450);
DISPLAY INVISIBLE (-2948 5450);
FORCEADD TAP..6
R 2
(-2950 5150);
FORCEPROP 3 LASTPIN (-3000 5150) SIG_NAME P5E_CPU1_P0_TX_DP<4>
J 0
(-2990 5160);
DISPLAY 0.659574 (-2990 5160);
PAINT MONO (-2990 5160);
DISPLAY INVISIBLE (-2990 5160);
FORCEPROP 1 LASTPIN (-3000 5150) BN 4
J 2
(-2948 5158);
DISPLAY 0.489362 (-2948 5158);
PAINT MONO (-2948 5158);
FORCEPROP 2 LAST ROOM RISER1
J 0
(-3450 5200);
DISPLAY 0.829787 (-3450 5200);
PAINT RED (-3450 5200);
DISPLAY INVISIBLE (-3450 5200);
FORCEPROP 2 LAST BOM_COST IO_SLOT
J 0
(-3450 5250);
DISPLAY 0.829787 (-3450 5250);
DISPLAY INVISIBLE (-3450 5250);
FORCEPROP 2 LAST CDS_LIB standard
J 0
(-2950 5150);
DISPLAY INVISIBLE (-2950 5150);
FORCEPROP 1 LAST BODY_TYPE PLUMBING
J 2
(-2950 5100);
DISPLAY 0.702128 (-2950 5100);
PAINT GREEN (-2950 5100);
DISPLAY INVISIBLE (-2950 5100);
FORCEPROP 1 LAST HDL_TAP TRUE
J 2
(-3275 5025);
DISPLAY 0.702128 (-3275 5025);
PAINT GREEN (-3275 5025);
DISPLAY INVISIBLE (-3275 5025);
FORCEPROP 1 LAST PATH I299
J 2
(-2948 5150);
DISPLAY 0.872340 (-2948 5150);
PAINT GREEN (-2948 5150);
DISPLAY INVISIBLE (-2948 5150);
FORCEADD TAP..6
R 2
(-2950 5250);
FORCEPROP 3 LASTPIN (-3000 5250) SIG_NAME P5E_CPU1_P0_TX_DP<3>
J 0
(-2990 5260);
DISPLAY 0.659574 (-2990 5260);
PAINT MONO (-2990 5260);
DISPLAY INVISIBLE (-2990 5260);
FORCEPROP 1 LASTPIN (-3000 5250) BN 3
J 2
(-2948 5258);
DISPLAY 0.489362 (-2948 5258);
PAINT MONO (-2948 5258);
FORCEPROP 2 LAST ROOM RISER1
J 0
(-3450 5300);
DISPLAY 0.829787 (-3450 5300);
PAINT RED (-3450 5300);
DISPLAY INVISIBLE (-3450 5300);
FORCEPROP 2 LAST BOM_COST IO_SLOT
J 0
(-3450 5350);
DISPLAY 0.829787 (-3450 5350);
DISPLAY INVISIBLE (-3450 5350);
FORCEPROP 2 LAST CDS_LIB standard
J 0
(-2950 5250);
DISPLAY INVISIBLE (-2950 5250);
FORCEPROP 1 LAST BODY_TYPE PLUMBING
J 2
(-2950 5200);
DISPLAY 0.702128 (-2950 5200);
PAINT GREEN (-2950 5200);
DISPLAY INVISIBLE (-2950 5200);
FORCEPROP 1 LAST HDL_TAP TRUE
J 2
(-3275 5125);
DISPLAY 0.702128 (-3275 5125);
PAINT GREEN (-3275 5125);
DISPLAY INVISIBLE (-3275 5125);
FORCEPROP 1 LAST PATH I300
J 2
(-2948 5250);
DISPLAY 0.872340 (-2948 5250);
PAINT GREEN (-2948 5250);
DISPLAY INVISIBLE (-2948 5250);
FORCEADD TAP..6
R 2
(-2950 5050);
FORCEPROP 3 LASTPIN (-3000 5050) SIG_NAME P5E_CPU1_P0_TX_DP<5>
J 0
(-2990 5060);
DISPLAY 0.659574 (-2990 5060);
PAINT MONO (-2990 5060);
DISPLAY INVISIBLE (-2990 5060);
FORCEPROP 1 LASTPIN (-3000 5050) BN 5
J 2
(-2948 5058);
DISPLAY 0.489362 (-2948 5058);
PAINT MONO (-2948 5058);
FORCEPROP 2 LAST ROOM RISER1
J 0
(-3450 5100);
DISPLAY 0.829787 (-3450 5100);
PAINT RED (-3450 5100);
DISPLAY INVISIBLE (-3450 5100);
FORCEPROP 2 LAST BOM_COST IO_SLOT
J 0
(-3450 5150);
DISPLAY 0.829787 (-3450 5150);
DISPLAY INVISIBLE (-3450 5150);
FORCEPROP 2 LAST CDS_LIB standard
J 0
(-2950 5050);
DISPLAY INVISIBLE (-2950 5050);
FORCEPROP 1 LAST BODY_TYPE PLUMBING
J 2
(-2950 5000);
DISPLAY 0.702128 (-2950 5000);
PAINT GREEN (-2950 5000);
DISPLAY INVISIBLE (-2950 5000);
FORCEPROP 1 LAST HDL_TAP TRUE
J 2
(-3275 4925);
DISPLAY 0.702128 (-3275 4925);
PAINT GREEN (-3275 4925);
DISPLAY INVISIBLE (-3275 4925);
FORCEPROP 1 LAST PATH I301
J 2
(-2948 5050);
DISPLAY 0.872340 (-2948 5050);
PAINT GREEN (-2948 5050);
DISPLAY INVISIBLE (-2948 5050);
FORCEADD TAP..6
R 2
(-2950 4950);
FORCEPROP 3 LASTPIN (-3000 4950) SIG_NAME P5E_CPU1_P0_TX_DP<6>
J 0
(-2990 4960);
DISPLAY 0.659574 (-2990 4960);
PAINT MONO (-2990 4960);
DISPLAY INVISIBLE (-2990 4960);
FORCEPROP 1 LASTPIN (-3000 4950) BN 6
J 2
(-2948 4958);
DISPLAY 0.489362 (-2948 4958);
PAINT MONO (-2948 4958);
FORCEPROP 2 LAST ROOM RISER1
J 0
(-3450 5000);
DISPLAY 0.829787 (-3450 5000);
PAINT RED (-3450 5000);
DISPLAY INVISIBLE (-3450 5000);
FORCEPROP 2 LAST BOM_COST IO_SLOT
J 0
(-3450 5050);
DISPLAY 0.829787 (-3450 5050);
DISPLAY INVISIBLE (-3450 5050);
FORCEPROP 2 LAST CDS_LIB standard
J 0
(-2950 4950);
DISPLAY INVISIBLE (-2950 4950);
FORCEPROP 1 LAST BODY_TYPE PLUMBING
J 2
(-2950 4900);
DISPLAY 0.702128 (-2950 4900);
PAINT GREEN (-2950 4900);
DISPLAY INVISIBLE (-2950 4900);
FORCEPROP 1 LAST HDL_TAP TRUE
J 2
(-3275 4825);
DISPLAY 0.702128 (-3275 4825);
PAINT GREEN (-3275 4825);
DISPLAY INVISIBLE (-3275 4825);
FORCEPROP 1 LAST PATH I305
J 2
(-2948 4950);
DISPLAY 0.872340 (-2948 4950);
PAINT GREEN (-2948 4950);
DISPLAY INVISIBLE (-2948 4950);
FORCEADD TAP..6
R 2
(-2950 4850);
FORCEPROP 3 LASTPIN (-3000 4850) SIG_NAME P5E_CPU1_P0_TX_DP<7>
J 0
(-2990 4860);
DISPLAY 0.659574 (-2990 4860);
PAINT MONO (-2990 4860);
DISPLAY INVISIBLE (-2990 4860);
FORCEPROP 1 LASTPIN (-3000 4850) BN 7
J 2
(-2948 4858);
DISPLAY 0.489362 (-2948 4858);
PAINT MONO (-2948 4858);
FORCEPROP 2 LAST ROOM RISER1
J 0
(-3450 4900);
DISPLAY 0.829787 (-3450 4900);
PAINT RED (-3450 4900);
DISPLAY INVISIBLE (-3450 4900);
FORCEPROP 2 LAST BOM_COST IO_SLOT
J 0
(-3450 4950);
DISPLAY 0.829787 (-3450 4950);
DISPLAY INVISIBLE (-3450 4950);
FORCEPROP 2 LAST CDS_LIB standard
J 0
(-2950 4850);
DISPLAY INVISIBLE (-2950 4850);
FORCEPROP 1 LAST BODY_TYPE PLUMBING
J 2
(-2950 4800);
DISPLAY 0.702128 (-2950 4800);
PAINT GREEN (-2950 4800);
DISPLAY INVISIBLE (-2950 4800);
FORCEPROP 1 LAST HDL_TAP TRUE
J 2
(-3275 4725);
DISPLAY 0.702128 (-3275 4725);
PAINT GREEN (-3275 4725);
DISPLAY INVISIBLE (-3275 4725);
FORCEPROP 1 LAST PATH I306
J 2
(-2948 4850);
DISPLAY 0.872340 (-2948 4850);
PAINT GREEN (-2948 4850);
DISPLAY INVISIBLE (-2948 4850);
FORCEADD TAP..6
R 2
(-2950 4750);
FORCEPROP 3 LASTPIN (-3000 4750) SIG_NAME P5E_CPU1_P0_TX_DP<8>
J 0
(-2990 4760);
DISPLAY 0.659574 (-2990 4760);
PAINT MONO (-2990 4760);
DISPLAY INVISIBLE (-2990 4760);
FORCEPROP 1 LASTPIN (-3000 4750) BN 8
J 2
(-2948 4758);
DISPLAY 0.489362 (-2948 4758);
PAINT MONO (-2948 4758);
FORCEPROP 2 LAST ROOM RISER1
J 0
(-3450 4800);
DISPLAY 0.829787 (-3450 4800);
PAINT RED (-3450 4800);
DISPLAY INVISIBLE (-3450 4800);
FORCEPROP 2 LAST BOM_COST IO_SLOT
J 0
(-3450 4850);
DISPLAY 0.829787 (-3450 4850);
DISPLAY INVISIBLE (-3450 4850);
FORCEPROP 2 LAST CDS_LIB standard
J 0
(-2950 4750);
DISPLAY INVISIBLE (-2950 4750);
FORCEPROP 1 LAST BODY_TYPE PLUMBING
J 2
(-2950 4700);
DISPLAY 0.702128 (-2950 4700);
PAINT GREEN (-2950 4700);
DISPLAY INVISIBLE (-2950 4700);
FORCEPROP 1 LAST HDL_TAP TRUE
J 2
(-3275 4625);
DISPLAY 0.702128 (-3275 4625);
PAINT GREEN (-3275 4625);
DISPLAY INVISIBLE (-3275 4625);
FORCEPROP 1 LAST PATH I307
J 2
(-2948 4750);
DISPLAY 0.872340 (-2948 4750);
PAINT GREEN (-2948 4750);
DISPLAY INVISIBLE (-2948 4750);
FORCEADD TAP..6
R 2
(-2950 4650);
FORCEPROP 3 LASTPIN (-3000 4650) SIG_NAME P5E_CPU1_P0_TX_DP<9>
J 0
(-2990 4660);
DISPLAY 0.659574 (-2990 4660);
PAINT MONO (-2990 4660);
DISPLAY INVISIBLE (-2990 4660);
FORCEPROP 1 LASTPIN (-3000 4650) BN 9
J 2
(-2948 4658);
DISPLAY 0.489362 (-2948 4658);
PAINT MONO (-2948 4658);
FORCEPROP 2 LAST ROOM RISER1
J 0
(-3450 4700);
DISPLAY 0.829787 (-3450 4700);
PAINT RED (-3450 4700);
DISPLAY INVISIBLE (-3450 4700);
FORCEPROP 2 LAST BOM_COST IO_SLOT
J 0
(-3450 4750);
DISPLAY 0.829787 (-3450 4750);
DISPLAY INVISIBLE (-3450 4750);
FORCEPROP 2 LAST CDS_LIB standard
J 0
(-2950 4650);
DISPLAY INVISIBLE (-2950 4650);
FORCEPROP 1 LAST BODY_TYPE PLUMBING
J 2
(-2950 4600);
DISPLAY 0.702128 (-2950 4600);
PAINT GREEN (-2950 4600);
DISPLAY INVISIBLE (-2950 4600);
FORCEPROP 1 LAST HDL_TAP TRUE
J 2
(-3275 4525);
DISPLAY 0.702128 (-3275 4525);
PAINT GREEN (-3275 4525);
DISPLAY INVISIBLE (-3275 4525);
FORCEPROP 1 LAST PATH I311
J 2
(-2948 4650);
DISPLAY 0.872340 (-2948 4650);
PAINT GREEN (-2948 4650);
DISPLAY INVISIBLE (-2948 4650);
FORCEADD TAP..6
R 2
(-2950 4550);
FORCEPROP 3 LASTPIN (-3000 4550) SIG_NAME P5E_CPU1_P0_TX_DP<10>
J 0
(-2990 4560);
DISPLAY 0.659574 (-2990 4560);
PAINT MONO (-2990 4560);
DISPLAY INVISIBLE (-2990 4560);
FORCEPROP 1 LASTPIN (-3000 4550) BN 10
J 2
(-2948 4558);
DISPLAY 0.489362 (-2948 4558);
PAINT MONO (-2948 4558);
FORCEPROP 2 LAST ROOM RISER1
J 0
(-3450 4600);
DISPLAY 0.829787 (-3450 4600);
PAINT RED (-3450 4600);
DISPLAY INVISIBLE (-3450 4600);
FORCEPROP 2 LAST BOM_COST IO_SLOT
J 0
(-3450 4650);
DISPLAY 0.829787 (-3450 4650);
DISPLAY INVISIBLE (-3450 4650);
FORCEPROP 2 LAST CDS_LIB standard
J 0
(-2950 4550);
DISPLAY INVISIBLE (-2950 4550);
FORCEPROP 1 LAST BODY_TYPE PLUMBING
J 2
(-2950 4500);
DISPLAY 0.702128 (-2950 4500);
PAINT GREEN (-2950 4500);
DISPLAY INVISIBLE (-2950 4500);
FORCEPROP 1 LAST HDL_TAP TRUE
J 2
(-3275 4425);
DISPLAY 0.702128 (-3275 4425);
PAINT GREEN (-3275 4425);
DISPLAY INVISIBLE (-3275 4425);
FORCEPROP 1 LAST PATH I312
J 2
(-2948 4550);
DISPLAY 0.872340 (-2948 4550);
PAINT GREEN (-2948 4550);
DISPLAY INVISIBLE (-2948 4550);
FORCEADD TAP..6
R 2
(-2950 4450);
FORCEPROP 3 LASTPIN (-3000 4450) SIG_NAME P5E_CPU1_P0_TX_DP<11>
J 0
(-2990 4460);
DISPLAY 0.659574 (-2990 4460);
PAINT MONO (-2990 4460);
DISPLAY INVISIBLE (-2990 4460);
FORCEPROP 1 LASTPIN (-3000 4450) BN 11
J 2
(-2948 4458);
DISPLAY 0.489362 (-2948 4458);
PAINT MONO (-2948 4458);
FORCEPROP 2 LAST ROOM RISER1
J 0
(-3450 4500);
DISPLAY 0.829787 (-3450 4500);
PAINT RED (-3450 4500);
DISPLAY INVISIBLE (-3450 4500);
FORCEPROP 2 LAST BOM_COST IO_SLOT
J 0
(-3450 4550);
DISPLAY 0.829787 (-3450 4550);
DISPLAY INVISIBLE (-3450 4550);
FORCEPROP 2 LAST CDS_LIB standard
J 0
(-2950 4450);
DISPLAY INVISIBLE (-2950 4450);
FORCEPROP 1 LAST BODY_TYPE PLUMBING
J 2
(-2950 4400);
DISPLAY 0.702128 (-2950 4400);
PAINT GREEN (-2950 4400);
DISPLAY INVISIBLE (-2950 4400);
FORCEPROP 1 LAST HDL_TAP TRUE
J 2
(-3275 4325);
DISPLAY 0.702128 (-3275 4325);
PAINT GREEN (-3275 4325);
DISPLAY INVISIBLE (-3275 4325);
FORCEPROP 1 LAST PATH I315
J 2
(-2948 4450);
DISPLAY 0.872340 (-2948 4450);
PAINT GREEN (-2948 4450);
DISPLAY INVISIBLE (-2948 4450);
FORCEADD TAP..6
R 2
(-2950 4350);
FORCEPROP 3 LASTPIN (-3000 4350) SIG_NAME P5E_CPU1_P0_TX_DP<12>
J 0
(-2990 4360);
DISPLAY 0.659574 (-2990 4360);
PAINT MONO (-2990 4360);
DISPLAY INVISIBLE (-2990 4360);
FORCEPROP 1 LASTPIN (-3000 4350) BN 12
J 2
(-2948 4358);
DISPLAY 0.489362 (-2948 4358);
PAINT MONO (-2948 4358);
FORCEPROP 2 LAST ROOM RISER1
J 0
(-3450 4400);
DISPLAY 0.829787 (-3450 4400);
PAINT RED (-3450 4400);
DISPLAY INVISIBLE (-3450 4400);
FORCEPROP 2 LAST BOM_COST IO_SLOT
J 0
(-3450 4450);
DISPLAY 0.829787 (-3450 4450);
DISPLAY INVISIBLE (-3450 4450);
FORCEPROP 2 LAST CDS_LIB standard
J 0
(-2950 4350);
DISPLAY INVISIBLE (-2950 4350);
FORCEPROP 1 LAST BODY_TYPE PLUMBING
J 2
(-2950 4300);
DISPLAY 0.702128 (-2950 4300);
PAINT GREEN (-2950 4300);
DISPLAY INVISIBLE (-2950 4300);
FORCEPROP 1 LAST HDL_TAP TRUE
J 2
(-3275 4225);
DISPLAY 0.702128 (-3275 4225);
PAINT GREEN (-3275 4225);
DISPLAY INVISIBLE (-3275 4225);
FORCEPROP 1 LAST PATH I316
J 2
(-2948 4350);
DISPLAY 0.872340 (-2948 4350);
PAINT GREEN (-2948 4350);
DISPLAY INVISIBLE (-2948 4350);
FORCEADD TAP..6
R 2
(-2950 4250);
FORCEPROP 3 LASTPIN (-3000 4250) SIG_NAME P5E_CPU1_P0_TX_DP<13>
J 0
(-2990 4260);
DISPLAY 0.659574 (-2990 4260);
PAINT MONO (-2990 4260);
DISPLAY INVISIBLE (-2990 4260);
FORCEPROP 1 LASTPIN (-3000 4250) BN 13
J 2
(-2948 4258);
DISPLAY 0.489362 (-2948 4258);
PAINT MONO (-2948 4258);
FORCEPROP 2 LAST ROOM RISER1
J 0
(-3450 4300);
DISPLAY 0.829787 (-3450 4300);
PAINT RED (-3450 4300);
DISPLAY INVISIBLE (-3450 4300);
FORCEPROP 2 LAST BOM_COST IO_SLOT
J 0
(-3450 4350);
DISPLAY 0.829787 (-3450 4350);
DISPLAY INVISIBLE (-3450 4350);
FORCEPROP 2 LAST CDS_LIB standard
J 0
(-2950 4250);
DISPLAY INVISIBLE (-2950 4250);
FORCEPROP 1 LAST BODY_TYPE PLUMBING
J 2
(-2950 4200);
DISPLAY 0.702128 (-2950 4200);
PAINT GREEN (-2950 4200);
DISPLAY INVISIBLE (-2950 4200);
FORCEPROP 1 LAST HDL_TAP TRUE
J 2
(-3275 4125);
DISPLAY 0.702128 (-3275 4125);
PAINT GREEN (-3275 4125);
DISPLAY INVISIBLE (-3275 4125);
FORCEPROP 1 LAST PATH I317
J 2
(-2948 4250);
DISPLAY 0.872340 (-2948 4250);
PAINT GREEN (-2948 4250);
DISPLAY INVISIBLE (-2948 4250);
FORCEADD TAP..6
R 2
(-2950 4150);
FORCEPROP 3 LASTPIN (-3000 4150) SIG_NAME P5E_CPU1_P0_TX_DP<14>
J 0
(-2990 4160);
DISPLAY 0.659574 (-2990 4160);
PAINT MONO (-2990 4160);
DISPLAY INVISIBLE (-2990 4160);
FORCEPROP 1 LASTPIN (-3000 4150) BN 14
J 2
(-2948 4158);
DISPLAY 0.489362 (-2948 4158);
PAINT MONO (-2948 4158);
FORCEPROP 2 LAST ROOM RISER1
J 0
(-3450 4200);
DISPLAY 0.829787 (-3450 4200);
PAINT RED (-3450 4200);
DISPLAY INVISIBLE (-3450 4200);
FORCEPROP 2 LAST BOM_COST IO_SLOT
J 0
(-3450 4250);
DISPLAY 0.829787 (-3450 4250);
DISPLAY INVISIBLE (-3450 4250);
FORCEPROP 2 LAST CDS_LIB standard
J 0
(-2950 4150);
DISPLAY INVISIBLE (-2950 4150);
FORCEPROP 1 LAST BODY_TYPE PLUMBING
J 2
(-2950 4100);
DISPLAY 0.702128 (-2950 4100);
PAINT GREEN (-2950 4100);
DISPLAY INVISIBLE (-2950 4100);
FORCEPROP 1 LAST HDL_TAP TRUE
J 2
(-3275 4025);
DISPLAY 0.702128 (-3275 4025);
PAINT GREEN (-3275 4025);
DISPLAY INVISIBLE (-3275 4025);
FORCEPROP 1 LAST PATH I321
J 2
(-2948 4150);
DISPLAY 0.872340 (-2948 4150);
PAINT GREEN (-2948 4150);
DISPLAY INVISIBLE (-2948 4150);
FORCEADD TAP..6
R 2
(-2950 4050);
FORCEPROP 3 LASTPIN (-3000 4050) SIG_NAME P5E_CPU1_P0_TX_DP<15>
J 0
(-2990 4060);
DISPLAY 0.659574 (-2990 4060);
PAINT MONO (-2990 4060);
DISPLAY INVISIBLE (-2990 4060);
FORCEPROP 1 LASTPIN (-3000 4050) BN 15
J 2
(-2948 4058);
DISPLAY 0.489362 (-2948 4058);
PAINT MONO (-2948 4058);
FORCEPROP 2 LAST ROOM RISER1
J 0
(-3450 4100);
DISPLAY 0.829787 (-3450 4100);
PAINT RED (-3450 4100);
DISPLAY INVISIBLE (-3450 4100);
FORCEPROP 2 LAST BOM_COST IO_SLOT
J 0
(-3450 4150);
DISPLAY 0.829787 (-3450 4150);
DISPLAY INVISIBLE (-3450 4150);
FORCEPROP 2 LAST CDS_LIB standard
J 0
(-2950 4050);
DISPLAY INVISIBLE (-2950 4050);
FORCEPROP 1 LAST BODY_TYPE PLUMBING
J 2
(-2950 4000);
DISPLAY 0.702128 (-2950 4000);
PAINT GREEN (-2950 4000);
DISPLAY INVISIBLE (-2950 4000);
FORCEPROP 1 LAST HDL_TAP TRUE
J 2
(-3275 3925);
DISPLAY 0.702128 (-3275 3925);
PAINT GREEN (-3275 3925);
DISPLAY INVISIBLE (-3275 3925);
FORCEPROP 1 LAST PATH I322
J 2
(-2948 4050);
DISPLAY 0.872340 (-2948 4050);
PAINT GREEN (-2948 4050);
DISPLAY INVISIBLE (-2948 4050);
FORCEADD TAP..6
(-6600 5500);
FORCEPROP 3 LASTPIN (-6550 5500) SIG_NAME P5E_CPU1_P0_RX_DN<0>
J 0
(-6540 5510);
DISPLAY 0.659574 (-6540 5510);
PAINT MONO (-6540 5510);
DISPLAY INVISIBLE (-6540 5510);
FORCEPROP 1 LASTPIN (-6550 5500) BN 0
J 0
(-6602 5508);
DISPLAY 0.489362 (-6602 5508);
PAINT MONO (-6602 5508);
FORCEPROP 2 LAST CDS_LIB mstr_standard
J 0
(-6600 5500);
DISPLAY INVISIBLE (-6600 5500);
FORCEPROP 1 LAST BODY_TYPE PLUMBING
J 0
(-6600 5450);
DISPLAY 0.574468 (-6600 5450);
PAINT GREEN (-6600 5450);
DISPLAY INVISIBLE (-6600 5450);
FORCEPROP 1 LAST HDL_TAP TRUE
J 0
(-6275 5375);
DISPLAY 0.574468 (-6275 5375);
PAINT GREEN (-6275 5375);
DISPLAY INVISIBLE (-6275 5375);
FORCEPROP 1 LAST PATH I323
J 0
(-6602 5500);
DISPLAY 0.872340 (-6602 5500);
PAINT GREEN (-6602 5500);
DISPLAY INVISIBLE (-6602 5500);
FORCEADD TAP..6
(-6600 5400);
FORCEPROP 3 LASTPIN (-6550 5400) SIG_NAME P5E_CPU1_P0_RX_DN<1>
J 0
(-6540 5410);
DISPLAY 0.659574 (-6540 5410);
PAINT MONO (-6540 5410);
DISPLAY INVISIBLE (-6540 5410);
FORCEPROP 1 LASTPIN (-6550 5400) BN 1
J 0
(-6602 5408);
DISPLAY 0.489362 (-6602 5408);
PAINT MONO (-6602 5408);
FORCEPROP 2 LAST CDS_LIB mstr_standard
J 0
(-6600 5400);
DISPLAY INVISIBLE (-6600 5400);
FORCEPROP 1 LAST BODY_TYPE PLUMBING
J 0
(-6600 5350);
DISPLAY 0.574468 (-6600 5350);
PAINT GREEN (-6600 5350);
DISPLAY INVISIBLE (-6600 5350);
FORCEPROP 1 LAST HDL_TAP TRUE
J 0
(-6275 5275);
DISPLAY 0.574468 (-6275 5275);
PAINT GREEN (-6275 5275);
DISPLAY INVISIBLE (-6275 5275);
FORCEPROP 1 LAST PATH I324
J 0
(-6602 5400);
DISPLAY 0.872340 (-6602 5400);
PAINT GREEN (-6602 5400);
DISPLAY INVISIBLE (-6602 5400);
FORCEADD TAP..6
(-6600 5300);
FORCEPROP 3 LASTPIN (-6550 5300) SIG_NAME P5E_CPU1_P0_RX_DN<2>
J 0
(-6540 5310);
DISPLAY 0.659574 (-6540 5310);
PAINT MONO (-6540 5310);
DISPLAY INVISIBLE (-6540 5310);
FORCEPROP 1 LASTPIN (-6550 5300) BN 2
J 0
(-6602 5308);
DISPLAY 0.489362 (-6602 5308);
PAINT MONO (-6602 5308);
FORCEPROP 2 LAST CDS_LIB standard
J 0
(-6600 5300);
DISPLAY INVISIBLE (-6600 5300);
FORCEPROP 1 LAST BODY_TYPE PLUMBING
J 0
(-6600 5250);
DISPLAY 0.574468 (-6600 5250);
PAINT GREEN (-6600 5250);
DISPLAY INVISIBLE (-6600 5250);
FORCEPROP 1 LAST HDL_TAP TRUE
J 0
(-6275 5175);
DISPLAY 0.574468 (-6275 5175);
PAINT GREEN (-6275 5175);
DISPLAY INVISIBLE (-6275 5175);
FORCEPROP 1 LAST PATH I325
J 0
(-6602 5300);
DISPLAY 0.872340 (-6602 5300);
PAINT GREEN (-6602 5300);
DISPLAY INVISIBLE (-6602 5300);
FORCEADD TAP..6
(-6600 5200);
FORCEPROP 3 LASTPIN (-6550 5200) SIG_NAME P5E_CPU1_P0_RX_DN<3>
J 0
(-6540 5210);
DISPLAY 0.659574 (-6540 5210);
PAINT MONO (-6540 5210);
DISPLAY INVISIBLE (-6540 5210);
FORCEPROP 1 LASTPIN (-6550 5200) BN 3
J 0
(-6602 5208);
DISPLAY 0.489362 (-6602 5208);
PAINT MONO (-6602 5208);
FORCEPROP 2 LAST CDS_LIB standard
J 0
(-6600 5200);
DISPLAY INVISIBLE (-6600 5200);
FORCEPROP 1 LAST BODY_TYPE PLUMBING
J 0
(-6600 5150);
DISPLAY 0.574468 (-6600 5150);
PAINT GREEN (-6600 5150);
DISPLAY INVISIBLE (-6600 5150);
FORCEPROP 1 LAST HDL_TAP TRUE
J 0
(-6275 5075);
DISPLAY 0.574468 (-6275 5075);
PAINT GREEN (-6275 5075);
DISPLAY INVISIBLE (-6275 5075);
FORCEPROP 1 LAST PATH I326
J 0
(-6602 5200);
DISPLAY 0.872340 (-6602 5200);
PAINT GREEN (-6602 5200);
DISPLAY INVISIBLE (-6602 5200);
FORCEADD TAP..6
(-6600 5100);
FORCEPROP 3 LASTPIN (-6550 5100) SIG_NAME P5E_CPU1_P0_RX_DN<4>
J 0
(-6540 5110);
DISPLAY 0.659574 (-6540 5110);
PAINT MONO (-6540 5110);
DISPLAY INVISIBLE (-6540 5110);
FORCEPROP 1 LASTPIN (-6550 5100) BN 4
J 0
(-6602 5108);
DISPLAY 0.489362 (-6602 5108);
PAINT MONO (-6602 5108);
FORCEPROP 2 LAST CDS_LIB standard
J 0
(-6600 5100);
DISPLAY INVISIBLE (-6600 5100);
FORCEPROP 1 LAST BODY_TYPE PLUMBING
J 0
(-6600 5050);
DISPLAY 0.574468 (-6600 5050);
PAINT GREEN (-6600 5050);
DISPLAY INVISIBLE (-6600 5050);
FORCEPROP 1 LAST HDL_TAP TRUE
J 0
(-6275 4975);
DISPLAY 0.574468 (-6275 4975);
PAINT GREEN (-6275 4975);
DISPLAY INVISIBLE (-6275 4975);
FORCEPROP 1 LAST PATH I327
J 0
(-6602 5100);
DISPLAY 0.872340 (-6602 5100);
PAINT GREEN (-6602 5100);
DISPLAY INVISIBLE (-6602 5100);
FORCEADD TAP..6
(-6600 5000);
FORCEPROP 3 LASTPIN (-6550 5000) SIG_NAME P5E_CPU1_P0_RX_DN<5>
J 0
(-6540 5010);
DISPLAY 0.659574 (-6540 5010);
PAINT MONO (-6540 5010);
DISPLAY INVISIBLE (-6540 5010);
FORCEPROP 1 LASTPIN (-6550 5000) BN 5
J 0
(-6602 5008);
DISPLAY 0.489362 (-6602 5008);
PAINT MONO (-6602 5008);
FORCEPROP 2 LAST CDS_LIB standard
J 0
(-6600 5000);
DISPLAY INVISIBLE (-6600 5000);
FORCEPROP 1 LAST BODY_TYPE PLUMBING
J 0
(-6600 4950);
DISPLAY 0.574468 (-6600 4950);
PAINT GREEN (-6600 4950);
DISPLAY INVISIBLE (-6600 4950);
FORCEPROP 1 LAST HDL_TAP TRUE
J 0
(-6275 4875);
DISPLAY 0.574468 (-6275 4875);
PAINT GREEN (-6275 4875);
DISPLAY INVISIBLE (-6275 4875);
FORCEPROP 1 LAST PATH I328
J 0
(-6602 5000);
DISPLAY 0.872340 (-6602 5000);
PAINT GREEN (-6602 5000);
DISPLAY INVISIBLE (-6602 5000);
FORCEADD TAP..6
(-6600 4800);
FORCEPROP 3 LASTPIN (-6550 4800) SIG_NAME P5E_CPU1_P0_RX_DN<7>
J 0
(-6540 4810);
DISPLAY 0.659574 (-6540 4810);
PAINT MONO (-6540 4810);
DISPLAY INVISIBLE (-6540 4810);
FORCEPROP 1 LASTPIN (-6550 4800) BN 7
J 0
(-6602 4808);
DISPLAY 0.489362 (-6602 4808);
PAINT MONO (-6602 4808);
FORCEPROP 2 LAST CDS_LIB standard
J 0
(-6600 4800);
DISPLAY INVISIBLE (-6600 4800);
FORCEPROP 1 LAST BODY_TYPE PLUMBING
J 0
(-6600 4750);
DISPLAY 0.574468 (-6600 4750);
PAINT GREEN (-6600 4750);
DISPLAY INVISIBLE (-6600 4750);
FORCEPROP 1 LAST HDL_TAP TRUE
J 0
(-6275 4675);
DISPLAY 0.574468 (-6275 4675);
PAINT GREEN (-6275 4675);
DISPLAY INVISIBLE (-6275 4675);
FORCEPROP 1 LAST PATH I329
J 0
(-6602 4800);
DISPLAY 0.872340 (-6602 4800);
PAINT GREEN (-6602 4800);
DISPLAY INVISIBLE (-6602 4800);
FORCEADD TAP..6
(-6600 4900);
FORCEPROP 3 LASTPIN (-6550 4900) SIG_NAME P5E_CPU1_P0_RX_DN<6>
J 0
(-6540 4910);
DISPLAY 0.659574 (-6540 4910);
PAINT MONO (-6540 4910);
DISPLAY INVISIBLE (-6540 4910);
FORCEPROP 1 LASTPIN (-6550 4900) BN 6
J 0
(-6602 4908);
DISPLAY 0.489362 (-6602 4908);
PAINT MONO (-6602 4908);
FORCEPROP 2 LAST CDS_LIB standard
J 0
(-6600 4900);
DISPLAY INVISIBLE (-6600 4900);
FORCEPROP 1 LAST BODY_TYPE PLUMBING
J 0
(-6600 4850);
DISPLAY 0.574468 (-6600 4850);
PAINT GREEN (-6600 4850);
DISPLAY INVISIBLE (-6600 4850);
FORCEPROP 1 LAST HDL_TAP TRUE
J 0
(-6275 4775);
DISPLAY 0.574468 (-6275 4775);
PAINT GREEN (-6275 4775);
DISPLAY INVISIBLE (-6275 4775);
FORCEPROP 1 LAST PATH I330
J 0
(-6602 4900);
DISPLAY 0.872340 (-6602 4900);
PAINT GREEN (-6602 4900);
DISPLAY INVISIBLE (-6602 4900);
FORCEADD TAP..6
(-6600 4700);
FORCEPROP 3 LASTPIN (-6550 4700) SIG_NAME P5E_CPU1_P0_RX_DN<8>
J 0
(-6540 4710);
DISPLAY 0.659574 (-6540 4710);
PAINT MONO (-6540 4710);
DISPLAY INVISIBLE (-6540 4710);
FORCEPROP 1 LASTPIN (-6550 4700) BN 8
J 0
(-6602 4708);
DISPLAY 0.489362 (-6602 4708);
PAINT MONO (-6602 4708);
FORCEPROP 2 LAST CDS_LIB standard
J 0
(-6600 4700);
DISPLAY INVISIBLE (-6600 4700);
FORCEPROP 1 LAST BODY_TYPE PLUMBING
J 0
(-6600 4650);
DISPLAY 0.574468 (-6600 4650);
PAINT GREEN (-6600 4650);
DISPLAY INVISIBLE (-6600 4650);
FORCEPROP 1 LAST HDL_TAP TRUE
J 0
(-6275 4575);
DISPLAY 0.574468 (-6275 4575);
PAINT GREEN (-6275 4575);
DISPLAY INVISIBLE (-6275 4575);
FORCEPROP 1 LAST PATH I331
J 0
(-6602 4700);
DISPLAY 0.872340 (-6602 4700);
PAINT GREEN (-6602 4700);
DISPLAY INVISIBLE (-6602 4700);
FORCEADD TAP..6
(-6600 4600);
FORCEPROP 3 LASTPIN (-6550 4600) SIG_NAME P5E_CPU1_P0_RX_DN<9>
J 0
(-6540 4610);
DISPLAY 0.659574 (-6540 4610);
PAINT MONO (-6540 4610);
DISPLAY INVISIBLE (-6540 4610);
FORCEPROP 1 LASTPIN (-6550 4600) BN 9
J 0
(-6602 4608);
DISPLAY 0.489362 (-6602 4608);
PAINT MONO (-6602 4608);
FORCEPROP 2 LAST CDS_LIB standard
J 0
(-6600 4600);
DISPLAY INVISIBLE (-6600 4600);
FORCEPROP 1 LAST BODY_TYPE PLUMBING
J 0
(-6600 4550);
DISPLAY 0.574468 (-6600 4550);
PAINT GREEN (-6600 4550);
DISPLAY INVISIBLE (-6600 4550);
FORCEPROP 1 LAST HDL_TAP TRUE
J 0
(-6275 4475);
DISPLAY 0.574468 (-6275 4475);
PAINT GREEN (-6275 4475);
DISPLAY INVISIBLE (-6275 4475);
FORCEPROP 1 LAST PATH I332
J 0
(-6602 4600);
DISPLAY 0.872340 (-6602 4600);
PAINT GREEN (-6602 4600);
DISPLAY INVISIBLE (-6602 4600);
FORCEADD TAP..6
(-6600 4400);
FORCEPROP 3 LASTPIN (-6550 4400) SIG_NAME P5E_CPU1_P0_RX_DN<11>
J 0
(-6540 4410);
DISPLAY 0.659574 (-6540 4410);
PAINT MONO (-6540 4410);
DISPLAY INVISIBLE (-6540 4410);
FORCEPROP 1 LASTPIN (-6550 4400) BN 11
J 0
(-6602 4408);
DISPLAY 0.489362 (-6602 4408);
PAINT MONO (-6602 4408);
FORCEPROP 2 LAST CDS_LIB standard
J 0
(-6600 4400);
DISPLAY INVISIBLE (-6600 4400);
FORCEPROP 1 LAST BODY_TYPE PLUMBING
J 0
(-6600 4350);
DISPLAY 0.574468 (-6600 4350);
PAINT GREEN (-6600 4350);
DISPLAY INVISIBLE (-6600 4350);
FORCEPROP 1 LAST HDL_TAP TRUE
J 0
(-6275 4275);
DISPLAY 0.574468 (-6275 4275);
PAINT GREEN (-6275 4275);
DISPLAY INVISIBLE (-6275 4275);
FORCEPROP 1 LAST PATH I333
J 0
(-6602 4400);
DISPLAY 0.872340 (-6602 4400);
PAINT GREEN (-6602 4400);
DISPLAY INVISIBLE (-6602 4400);
FORCEADD TAP..6
(-6600 4500);
FORCEPROP 3 LASTPIN (-6550 4500) SIG_NAME P5E_CPU1_P0_RX_DN<10>
J 0
(-6540 4510);
DISPLAY 0.659574 (-6540 4510);
PAINT MONO (-6540 4510);
DISPLAY INVISIBLE (-6540 4510);
FORCEPROP 1 LASTPIN (-6550 4500) BN 10
J 0
(-6602 4508);
DISPLAY 0.489362 (-6602 4508);
PAINT MONO (-6602 4508);
FORCEPROP 2 LAST CDS_LIB standard
J 0
(-6600 4500);
DISPLAY INVISIBLE (-6600 4500);
FORCEPROP 1 LAST BODY_TYPE PLUMBING
J 0
(-6600 4450);
DISPLAY 0.574468 (-6600 4450);
PAINT GREEN (-6600 4450);
DISPLAY INVISIBLE (-6600 4450);
FORCEPROP 1 LAST HDL_TAP TRUE
J 0
(-6275 4375);
DISPLAY 0.574468 (-6275 4375);
PAINT GREEN (-6275 4375);
DISPLAY INVISIBLE (-6275 4375);
FORCEPROP 1 LAST PATH I334
J 0
(-6602 4500);
DISPLAY 0.872340 (-6602 4500);
PAINT GREEN (-6602 4500);
DISPLAY INVISIBLE (-6602 4500);
FORCEADD TAP..6
(-6600 4300);
FORCEPROP 3 LASTPIN (-6550 4300) SIG_NAME P5E_CPU1_P0_RX_DN<12>
J 0
(-6540 4310);
DISPLAY 0.659574 (-6540 4310);
PAINT MONO (-6540 4310);
DISPLAY INVISIBLE (-6540 4310);
FORCEPROP 1 LASTPIN (-6550 4300) BN 12
J 0
(-6602 4308);
DISPLAY 0.489362 (-6602 4308);
PAINT MONO (-6602 4308);
FORCEPROP 2 LAST CDS_LIB standard
J 0
(-6600 4300);
DISPLAY INVISIBLE (-6600 4300);
FORCEPROP 1 LAST BODY_TYPE PLUMBING
J 0
(-6600 4250);
DISPLAY 0.574468 (-6600 4250);
PAINT GREEN (-6600 4250);
DISPLAY INVISIBLE (-6600 4250);
FORCEPROP 1 LAST HDL_TAP TRUE
J 0
(-6275 4175);
DISPLAY 0.574468 (-6275 4175);
PAINT GREEN (-6275 4175);
DISPLAY INVISIBLE (-6275 4175);
FORCEPROP 1 LAST PATH I335
J 0
(-6602 4300);
DISPLAY 0.872340 (-6602 4300);
PAINT GREEN (-6602 4300);
DISPLAY INVISIBLE (-6602 4300);
FORCEADD TAP..6
(-6600 4200);
FORCEPROP 3 LASTPIN (-6550 4200) SIG_NAME P5E_CPU1_P0_RX_DN<13>
J 0
(-6540 4210);
DISPLAY 0.659574 (-6540 4210);
PAINT MONO (-6540 4210);
DISPLAY INVISIBLE (-6540 4210);
FORCEPROP 1 LASTPIN (-6550 4200) BN 13
J 0
(-6602 4208);
DISPLAY 0.489362 (-6602 4208);
PAINT MONO (-6602 4208);
FORCEPROP 2 LAST CDS_LIB standard
J 0
(-6600 4200);
DISPLAY INVISIBLE (-6600 4200);
FORCEPROP 1 LAST BODY_TYPE PLUMBING
J 0
(-6600 4150);
DISPLAY 0.574468 (-6600 4150);
PAINT GREEN (-6600 4150);
DISPLAY INVISIBLE (-6600 4150);
FORCEPROP 1 LAST HDL_TAP TRUE
J 0
(-6275 4075);
DISPLAY 0.574468 (-6275 4075);
PAINT GREEN (-6275 4075);
DISPLAY INVISIBLE (-6275 4075);
FORCEPROP 1 LAST PATH I336
J 0
(-6602 4200);
DISPLAY 0.872340 (-6602 4200);
PAINT GREEN (-6602 4200);
DISPLAY INVISIBLE (-6602 4200);
FORCEADD TAP..6
(-6600 4100);
FORCEPROP 3 LASTPIN (-6550 4100) SIG_NAME P5E_CPU1_P0_RX_DN<14>
J 0
(-6540 4110);
DISPLAY 0.659574 (-6540 4110);
PAINT MONO (-6540 4110);
DISPLAY INVISIBLE (-6540 4110);
FORCEPROP 1 LASTPIN (-6550 4100) BN 14
J 0
(-6602 4108);
DISPLAY 0.489362 (-6602 4108);
PAINT MONO (-6602 4108);
FORCEPROP 2 LAST CDS_LIB standard
J 0
(-6600 4100);
DISPLAY INVISIBLE (-6600 4100);
FORCEPROP 1 LAST BODY_TYPE PLUMBING
J 0
(-6600 4050);
DISPLAY 0.574468 (-6600 4050);
PAINT GREEN (-6600 4050);
DISPLAY INVISIBLE (-6600 4050);
FORCEPROP 1 LAST HDL_TAP TRUE
J 0
(-6275 3975);
DISPLAY 0.574468 (-6275 3975);
PAINT GREEN (-6275 3975);
DISPLAY INVISIBLE (-6275 3975);
FORCEPROP 1 LAST PATH I337
J 0
(-6602 4100);
DISPLAY 0.872340 (-6602 4100);
PAINT GREEN (-6602 4100);
DISPLAY INVISIBLE (-6602 4100);
FORCEADD TAP..6
(-6600 4000);
FORCEPROP 3 LASTPIN (-6550 4000) SIG_NAME P5E_CPU1_P0_RX_DN<15>
J 0
(-6540 4010);
DISPLAY 0.659574 (-6540 4010);
PAINT MONO (-6540 4010);
DISPLAY INVISIBLE (-6540 4010);
FORCEPROP 1 LASTPIN (-6550 4000) BN 15
J 0
(-6602 4008);
DISPLAY 0.489362 (-6602 4008);
PAINT MONO (-6602 4008);
FORCEPROP 2 LAST CDS_LIB standard
J 0
(-6600 4000);
DISPLAY INVISIBLE (-6600 4000);
FORCEPROP 1 LAST BODY_TYPE PLUMBING
J 0
(-6600 3950);
DISPLAY 0.574468 (-6600 3950);
PAINT GREEN (-6600 3950);
DISPLAY INVISIBLE (-6600 3950);
FORCEPROP 1 LAST HDL_TAP TRUE
J 0
(-6275 3875);
DISPLAY 0.574468 (-6275 3875);
PAINT GREEN (-6275 3875);
DISPLAY INVISIBLE (-6275 3875);
FORCEPROP 1 LAST PATH I338
J 0
(-6602 4000);
DISPLAY 0.872340 (-6602 4000);
PAINT GREEN (-6602 4000);
DISPLAY INVISIBLE (-6602 4000);
FORCEADD OFFPAGE..1
(-7550 5725);
FORCEPROP 2 LAST $XR0 318 
J 0
(-7802 5725);
DISPLAY 0.638298 (-7802 5725);
PAINT MONO (-7802 5725);
FORCEPROP 2 LAST CDS_LIB standard
J 0
(-7550 5725);
DISPLAY INVISIBLE (-7550 5725);
FORCEPROP 1 LAST OFFPAGE TRUE
J 0
(-7225 5600);
DISPLAY 0.872340 (-7225 5600);
PAINT GREEN (-7225 5600);
DISPLAY INVISIBLE (-7225 5600);
FORCEPROP 1 LAST COMMENT_BODY TRUE
J 0
(-7425 5625);
DISPLAY 0.872340 (-7425 5625);
PAINT GREEN (-7425 5625);
DISPLAY INVISIBLE (-7425 5625);
FORCEPROP 2 LAST PATH I339
J 0
(-7800 5775);
DISPLAY 0.680851 (-7800 5775);
DISPLAY INVISIBLE (-7800 5775);
FORCEADD TAP..6
R 2
(-2800 4400);
FORCEPROP 3 LASTPIN (-2850 4400) SIG_NAME P5E_CPU1_P0_TX_DN<11>
J 0
(-2840 4410);
DISPLAY 0.659574 (-2840 4410);
PAINT MONO (-2840 4410);
DISPLAY INVISIBLE (-2840 4410);
FORCEPROP 1 LASTPIN (-2850 4400) BN 11
J 2
(-2798 4408);
DISPLAY 0.489362 (-2798 4408);
PAINT MONO (-2798 4408);
FORCEPROP 2 LAST ROOM RISER1
J 0
(-3300 4450);
DISPLAY 0.829787 (-3300 4450);
PAINT RED (-3300 4450);
DISPLAY INVISIBLE (-3300 4450);
FORCEPROP 2 LAST BOM_COST IO_SLOT
J 0
(-3300 4500);
DISPLAY 0.829787 (-3300 4500);
DISPLAY INVISIBLE (-3300 4500);
FORCEPROP 2 LAST CDS_LIB standard
J 0
(-2800 4400);
DISPLAY INVISIBLE (-2800 4400);
FORCEPROP 1 LAST BODY_TYPE PLUMBING
J 2
(-2800 4350);
DISPLAY 0.702128 (-2800 4350);
PAINT GREEN (-2800 4350);
DISPLAY INVISIBLE (-2800 4350);
FORCEPROP 1 LAST HDL_TAP TRUE
J 2
(-3125 4275);
DISPLAY 0.702128 (-3125 4275);
PAINT GREEN (-3125 4275);
DISPLAY INVISIBLE (-3125 4275);
FORCEPROP 1 LAST PATH I340
J 2
(-2798 4400);
DISPLAY 0.872340 (-2798 4400);
PAINT GREEN (-2798 4400);
DISPLAY INVISIBLE (-2798 4400);
FORCEADD OFFPAGE..2
(-1825 5725);
FORCEPROP 2 LAST $XR0 65 
J 0
(-1636 5725);
DISPLAY 0.638298 (-1636 5725);
PAINT MONO (-1636 5725);
FORCEPROP 2 LAST CDS_LIB standard
J 0
(-1825 5725);
DISPLAY INVISIBLE (-1825 5725);
FORCEPROP 1 LAST OFFPAGE TRUE
J 0
(-1500 5600);
DISPLAY 0.872340 (-1500 5600);
PAINT GREEN (-1500 5600);
DISPLAY INVISIBLE (-1500 5600);
FORCEPROP 1 LAST COMMENT_BODY TRUE
J 0
(-1870 5630);
DISPLAY 0.872340 (-1870 5630);
PAINT GREEN (-1870 5630);
DISPLAY INVISIBLE (-1870 5630);
FORCEPROP 2 LAST PATH I341
J 0
(-1625 5775);
DISPLAY 0.680851 (-1625 5775);
DISPLAY INVISIBLE (-1625 5775);
FORCEADD TAP..6
R 2
(-2800 5500);
FORCEPROP 3 LASTPIN (-2850 5500) SIG_NAME P5E_CPU1_P0_TX_DN<0>
J 0
(-2840 5510);
DISPLAY 0.659574 (-2840 5510);
PAINT MONO (-2840 5510);
DISPLAY INVISIBLE (-2840 5510);
FORCEPROP 1 LASTPIN (-2850 5500) BN 0
J 2
(-2798 5508);
DISPLAY 0.489362 (-2798 5508);
PAINT MONO (-2798 5508);
FORCEPROP 2 LAST ROOM RISER1
J 0
(-3300 5550);
DISPLAY 0.829787 (-3300 5550);
PAINT RED (-3300 5550);
DISPLAY INVISIBLE (-3300 5550);
FORCEPROP 2 LAST CDS_LIB mstr_standard
J 0
(-2800 5500);
DISPLAY INVISIBLE (-2800 5500);
FORCEPROP 2 LAST BOM_COST IO_SLOT
J 0
(-3300 5600);
DISPLAY 0.829787 (-3300 5600);
DISPLAY INVISIBLE (-3300 5600);
FORCEPROP 1 LAST BODY_TYPE PLUMBING
J 2
(-2800 5450);
DISPLAY 0.702128 (-2800 5450);
PAINT GREEN (-2800 5450);
DISPLAY INVISIBLE (-2800 5450);
FORCEPROP 1 LAST HDL_TAP TRUE
J 2
(-3125 5375);
DISPLAY 0.702128 (-3125 5375);
PAINT GREEN (-3125 5375);
DISPLAY INVISIBLE (-3125 5375);
FORCEPROP 1 LAST PATH I342
J 2
(-2798 5500);
DISPLAY 0.872340 (-2798 5500);
PAINT GREEN (-2798 5500);
DISPLAY INVISIBLE (-2798 5500);
FORCEADD TAP..6
R 2
(-2800 5400);
FORCEPROP 3 LASTPIN (-2850 5400) SIG_NAME P5E_CPU1_P0_TX_DN<1>
J 0
(-2840 5410);
DISPLAY 0.659574 (-2840 5410);
PAINT MONO (-2840 5410);
DISPLAY INVISIBLE (-2840 5410);
FORCEPROP 1 LASTPIN (-2850 5400) BN 1
J 2
(-2798 5408);
DISPLAY 0.489362 (-2798 5408);
PAINT MONO (-2798 5408);
FORCEPROP 2 LAST ROOM RISER1
J 0
(-3300 5450);
DISPLAY 0.829787 (-3300 5450);
PAINT RED (-3300 5450);
DISPLAY INVISIBLE (-3300 5450);
FORCEPROP 2 LAST BOM_COST IO_SLOT
J 0
(-3300 5500);
DISPLAY 0.829787 (-3300 5500);
DISPLAY INVISIBLE (-3300 5500);
FORCEPROP 2 LAST CDS_LIB mstr_standard
J 0
(-2800 5400);
DISPLAY INVISIBLE (-2800 5400);
FORCEPROP 1 LAST BODY_TYPE PLUMBING
J 2
(-2800 5350);
DISPLAY 0.702128 (-2800 5350);
PAINT GREEN (-2800 5350);
DISPLAY INVISIBLE (-2800 5350);
FORCEPROP 1 LAST HDL_TAP TRUE
J 2
(-3125 5275);
DISPLAY 0.702128 (-3125 5275);
PAINT GREEN (-3125 5275);
DISPLAY INVISIBLE (-3125 5275);
FORCEPROP 1 LAST PATH I343
J 2
(-2798 5400);
DISPLAY 0.872340 (-2798 5400);
PAINT GREEN (-2798 5400);
DISPLAY INVISIBLE (-2798 5400);
FORCEADD TAP..6
R 2
(-2800 5300);
FORCEPROP 3 LASTPIN (-2850 5300) SIG_NAME P5E_CPU1_P0_TX_DN<2>
J 0
(-2840 5310);
DISPLAY 0.659574 (-2840 5310);
PAINT MONO (-2840 5310);
DISPLAY INVISIBLE (-2840 5310);
FORCEPROP 1 LASTPIN (-2850 5300) BN 2
J 2
(-2798 5308);
DISPLAY 0.489362 (-2798 5308);
PAINT MONO (-2798 5308);
FORCEPROP 2 LAST ROOM RISER1
J 0
(-3300 5350);
DISPLAY 0.829787 (-3300 5350);
PAINT RED (-3300 5350);
DISPLAY INVISIBLE (-3300 5350);
FORCEPROP 2 LAST BOM_COST IO_SLOT
J 0
(-3300 5400);
DISPLAY 0.829787 (-3300 5400);
DISPLAY INVISIBLE (-3300 5400);
FORCEPROP 2 LAST CDS_LIB standard
J 0
(-2800 5300);
DISPLAY INVISIBLE (-2800 5300);
FORCEPROP 1 LAST BODY_TYPE PLUMBING
J 2
(-2800 5250);
DISPLAY 0.702128 (-2800 5250);
PAINT GREEN (-2800 5250);
DISPLAY INVISIBLE (-2800 5250);
FORCEPROP 1 LAST HDL_TAP TRUE
J 2
(-3125 5175);
DISPLAY 0.702128 (-3125 5175);
PAINT GREEN (-3125 5175);
DISPLAY INVISIBLE (-3125 5175);
FORCEPROP 1 LAST PATH I344
J 2
(-2798 5300);
DISPLAY 0.872340 (-2798 5300);
PAINT GREEN (-2798 5300);
DISPLAY INVISIBLE (-2798 5300);
FORCEADD TAP..6
R 2
(-2800 5200);
FORCEPROP 3 LASTPIN (-2850 5200) SIG_NAME P5E_CPU1_P0_TX_DN<3>
J 0
(-2840 5210);
DISPLAY 0.659574 (-2840 5210);
PAINT MONO (-2840 5210);
DISPLAY INVISIBLE (-2840 5210);
FORCEPROP 1 LASTPIN (-2850 5200) BN 3
J 2
(-2798 5208);
DISPLAY 0.489362 (-2798 5208);
PAINT MONO (-2798 5208);
FORCEPROP 2 LAST ROOM RISER1
J 0
(-3300 5250);
DISPLAY 0.829787 (-3300 5250);
PAINT RED (-3300 5250);
DISPLAY INVISIBLE (-3300 5250);
FORCEPROP 2 LAST BOM_COST IO_SLOT
J 0
(-3300 5300);
DISPLAY 0.829787 (-3300 5300);
DISPLAY INVISIBLE (-3300 5300);
FORCEPROP 2 LAST CDS_LIB standard
J 0
(-2800 5200);
DISPLAY INVISIBLE (-2800 5200);
FORCEPROP 1 LAST BODY_TYPE PLUMBING
J 2
(-2800 5150);
DISPLAY 0.702128 (-2800 5150);
PAINT GREEN (-2800 5150);
DISPLAY INVISIBLE (-2800 5150);
FORCEPROP 1 LAST HDL_TAP TRUE
J 2
(-3125 5075);
DISPLAY 0.702128 (-3125 5075);
PAINT GREEN (-3125 5075);
DISPLAY INVISIBLE (-3125 5075);
FORCEPROP 1 LAST PATH I345
J 2
(-2798 5200);
DISPLAY 0.872340 (-2798 5200);
PAINT GREEN (-2798 5200);
DISPLAY INVISIBLE (-2798 5200);
FORCEADD TAP..6
R 2
(-2800 5100);
FORCEPROP 3 LASTPIN (-2850 5100) SIG_NAME P5E_CPU1_P0_TX_DN<4>
J 0
(-2840 5110);
DISPLAY 0.659574 (-2840 5110);
PAINT MONO (-2840 5110);
DISPLAY INVISIBLE (-2840 5110);
FORCEPROP 1 LASTPIN (-2850 5100) BN 4
J 2
(-2798 5108);
DISPLAY 0.489362 (-2798 5108);
PAINT MONO (-2798 5108);
FORCEPROP 2 LAST ROOM RISER1
J 0
(-3300 5150);
DISPLAY 0.829787 (-3300 5150);
PAINT RED (-3300 5150);
DISPLAY INVISIBLE (-3300 5150);
FORCEPROP 2 LAST BOM_COST IO_SLOT
J 0
(-3300 5200);
DISPLAY 0.829787 (-3300 5200);
DISPLAY INVISIBLE (-3300 5200);
FORCEPROP 2 LAST CDS_LIB standard
J 0
(-2800 5100);
DISPLAY INVISIBLE (-2800 5100);
FORCEPROP 1 LAST BODY_TYPE PLUMBING
J 2
(-2800 5050);
DISPLAY 0.702128 (-2800 5050);
PAINT GREEN (-2800 5050);
DISPLAY INVISIBLE (-2800 5050);
FORCEPROP 1 LAST HDL_TAP TRUE
J 2
(-3125 4975);
DISPLAY 0.702128 (-3125 4975);
PAINT GREEN (-3125 4975);
DISPLAY INVISIBLE (-3125 4975);
FORCEPROP 1 LAST PATH I346
J 2
(-2798 5100);
DISPLAY 0.872340 (-2798 5100);
PAINT GREEN (-2798 5100);
DISPLAY INVISIBLE (-2798 5100);
FORCEADD TAP..6
R 2
(-2800 5000);
FORCEPROP 3 LASTPIN (-2850 5000) SIG_NAME P5E_CPU1_P0_TX_DN<5>
J 0
(-2840 5010);
DISPLAY 0.659574 (-2840 5010);
PAINT MONO (-2840 5010);
DISPLAY INVISIBLE (-2840 5010);
FORCEPROP 1 LASTPIN (-2850 5000) BN 5
J 2
(-2798 5008);
DISPLAY 0.489362 (-2798 5008);
PAINT MONO (-2798 5008);
FORCEPROP 2 LAST ROOM RISER1
J 0
(-3300 5050);
DISPLAY 0.829787 (-3300 5050);
PAINT RED (-3300 5050);
DISPLAY INVISIBLE (-3300 5050);
FORCEPROP 2 LAST BOM_COST IO_SLOT
J 0
(-3300 5100);
DISPLAY 0.829787 (-3300 5100);
DISPLAY INVISIBLE (-3300 5100);
FORCEPROP 2 LAST CDS_LIB standard
J 0
(-2800 5000);
DISPLAY INVISIBLE (-2800 5000);
FORCEPROP 1 LAST BODY_TYPE PLUMBING
J 2
(-2800 4950);
DISPLAY 0.702128 (-2800 4950);
PAINT GREEN (-2800 4950);
DISPLAY INVISIBLE (-2800 4950);
FORCEPROP 1 LAST HDL_TAP TRUE
J 2
(-3125 4875);
DISPLAY 0.702128 (-3125 4875);
PAINT GREEN (-3125 4875);
DISPLAY INVISIBLE (-3125 4875);
FORCEPROP 1 LAST PATH I347
J 2
(-2798 5000);
DISPLAY 0.872340 (-2798 5000);
PAINT GREEN (-2798 5000);
DISPLAY INVISIBLE (-2798 5000);
FORCEADD TAP..6
R 2
(-2800 4900);
FORCEPROP 3 LASTPIN (-2850 4900) SIG_NAME P5E_CPU1_P0_TX_DN<6>
J 0
(-2840 4910);
DISPLAY 0.659574 (-2840 4910);
PAINT MONO (-2840 4910);
DISPLAY INVISIBLE (-2840 4910);
FORCEPROP 1 LASTPIN (-2850 4900) BN 6
J 2
(-2798 4908);
DISPLAY 0.489362 (-2798 4908);
PAINT MONO (-2798 4908);
FORCEPROP 2 LAST ROOM RISER1
J 0
(-3300 4950);
DISPLAY 0.829787 (-3300 4950);
PAINT RED (-3300 4950);
DISPLAY INVISIBLE (-3300 4950);
FORCEPROP 2 LAST BOM_COST IO_SLOT
J 0
(-3300 5000);
DISPLAY 0.829787 (-3300 5000);
DISPLAY INVISIBLE (-3300 5000);
FORCEPROP 2 LAST CDS_LIB standard
J 0
(-2800 4900);
DISPLAY INVISIBLE (-2800 4900);
FORCEPROP 1 LAST BODY_TYPE PLUMBING
J 2
(-2800 4850);
DISPLAY 0.702128 (-2800 4850);
PAINT GREEN (-2800 4850);
DISPLAY INVISIBLE (-2800 4850);
FORCEPROP 1 LAST HDL_TAP TRUE
J 2
(-3125 4775);
DISPLAY 0.702128 (-3125 4775);
PAINT GREEN (-3125 4775);
DISPLAY INVISIBLE (-3125 4775);
FORCEPROP 1 LAST PATH I348
J 2
(-2798 4900);
DISPLAY 0.872340 (-2798 4900);
PAINT GREEN (-2798 4900);
DISPLAY INVISIBLE (-2798 4900);
FORCEADD TAP..6
R 2
(-2800 4700);
FORCEPROP 3 LASTPIN (-2850 4700) SIG_NAME P5E_CPU1_P0_TX_DN<8>
J 0
(-2840 4710);
DISPLAY 0.659574 (-2840 4710);
PAINT MONO (-2840 4710);
DISPLAY INVISIBLE (-2840 4710);
FORCEPROP 1 LASTPIN (-2850 4700) BN 8
J 2
(-2798 4708);
DISPLAY 0.489362 (-2798 4708);
PAINT MONO (-2798 4708);
FORCEPROP 2 LAST ROOM RISER1
J 0
(-3300 4750);
DISPLAY 0.829787 (-3300 4750);
PAINT RED (-3300 4750);
DISPLAY INVISIBLE (-3300 4750);
FORCEPROP 2 LAST BOM_COST IO_SLOT
J 0
(-3300 4800);
DISPLAY 0.829787 (-3300 4800);
DISPLAY INVISIBLE (-3300 4800);
FORCEPROP 2 LAST CDS_LIB standard
J 0
(-2800 4700);
DISPLAY INVISIBLE (-2800 4700);
FORCEPROP 1 LAST BODY_TYPE PLUMBING
J 2
(-2800 4650);
DISPLAY 0.702128 (-2800 4650);
PAINT GREEN (-2800 4650);
DISPLAY INVISIBLE (-2800 4650);
FORCEPROP 1 LAST HDL_TAP TRUE
J 2
(-3125 4575);
DISPLAY 0.702128 (-3125 4575);
PAINT GREEN (-3125 4575);
DISPLAY INVISIBLE (-3125 4575);
FORCEPROP 1 LAST PATH I349
J 2
(-2798 4700);
DISPLAY 0.872340 (-2798 4700);
PAINT GREEN (-2798 4700);
DISPLAY INVISIBLE (-2798 4700);
FORCEADD TAP..6
R 2
(-2800 4800);
FORCEPROP 3 LASTPIN (-2850 4800) SIG_NAME P5E_CPU1_P0_TX_DN<7>
J 0
(-2840 4810);
DISPLAY 0.659574 (-2840 4810);
PAINT MONO (-2840 4810);
DISPLAY INVISIBLE (-2840 4810);
FORCEPROP 1 LASTPIN (-2850 4800) BN 7
J 2
(-2798 4808);
DISPLAY 0.489362 (-2798 4808);
PAINT MONO (-2798 4808);
FORCEPROP 2 LAST ROOM RISER1
J 0
(-3300 4850);
DISPLAY 0.829787 (-3300 4850);
PAINT RED (-3300 4850);
DISPLAY INVISIBLE (-3300 4850);
FORCEPROP 2 LAST BOM_COST IO_SLOT
J 0
(-3300 4900);
DISPLAY 0.829787 (-3300 4900);
DISPLAY INVISIBLE (-3300 4900);
FORCEPROP 2 LAST CDS_LIB standard
J 0
(-2800 4800);
DISPLAY INVISIBLE (-2800 4800);
FORCEPROP 1 LAST BODY_TYPE PLUMBING
J 2
(-2800 4750);
DISPLAY 0.702128 (-2800 4750);
PAINT GREEN (-2800 4750);
DISPLAY INVISIBLE (-2800 4750);
FORCEPROP 1 LAST HDL_TAP TRUE
J 2
(-3125 4675);
DISPLAY 0.702128 (-3125 4675);
PAINT GREEN (-3125 4675);
DISPLAY INVISIBLE (-3125 4675);
FORCEPROP 1 LAST PATH I350
J 2
(-2798 4800);
DISPLAY 0.872340 (-2798 4800);
PAINT GREEN (-2798 4800);
DISPLAY INVISIBLE (-2798 4800);
FORCEADD TAP..6
R 2
(-2800 4600);
FORCEPROP 3 LASTPIN (-2850 4600) SIG_NAME P5E_CPU1_P0_TX_DN<9>
J 0
(-2840 4610);
DISPLAY 0.659574 (-2840 4610);
PAINT MONO (-2840 4610);
DISPLAY INVISIBLE (-2840 4610);
FORCEPROP 1 LASTPIN (-2850 4600) BN 9
J 2
(-2798 4608);
DISPLAY 0.489362 (-2798 4608);
PAINT MONO (-2798 4608);
FORCEPROP 2 LAST ROOM RISER1
J 0
(-3300 4650);
DISPLAY 0.829787 (-3300 4650);
PAINT RED (-3300 4650);
DISPLAY INVISIBLE (-3300 4650);
FORCEPROP 2 LAST BOM_COST IO_SLOT
J 0
(-3300 4700);
DISPLAY 0.829787 (-3300 4700);
DISPLAY INVISIBLE (-3300 4700);
FORCEPROP 2 LAST CDS_LIB standard
J 0
(-2800 4600);
DISPLAY INVISIBLE (-2800 4600);
FORCEPROP 1 LAST BODY_TYPE PLUMBING
J 2
(-2800 4550);
DISPLAY 0.702128 (-2800 4550);
PAINT GREEN (-2800 4550);
DISPLAY INVISIBLE (-2800 4550);
FORCEPROP 1 LAST HDL_TAP TRUE
J 2
(-3125 4475);
DISPLAY 0.702128 (-3125 4475);
PAINT GREEN (-3125 4475);
DISPLAY INVISIBLE (-3125 4475);
FORCEPROP 1 LAST PATH I351
J 2
(-2798 4600);
DISPLAY 0.872340 (-2798 4600);
PAINT GREEN (-2798 4600);
DISPLAY INVISIBLE (-2798 4600);
FORCEADD TAP..6
R 2
(-2800 4500);
FORCEPROP 3 LASTPIN (-2850 4500) SIG_NAME P5E_CPU1_P0_TX_DN<10>
J 0
(-2840 4510);
DISPLAY 0.659574 (-2840 4510);
PAINT MONO (-2840 4510);
DISPLAY INVISIBLE (-2840 4510);
FORCEPROP 1 LASTPIN (-2850 4500) BN 10
J 2
(-2798 4508);
DISPLAY 0.489362 (-2798 4508);
PAINT MONO (-2798 4508);
FORCEPROP 2 LAST ROOM RISER1
J 0
(-3300 4550);
DISPLAY 0.829787 (-3300 4550);
PAINT RED (-3300 4550);
DISPLAY INVISIBLE (-3300 4550);
FORCEPROP 2 LAST BOM_COST IO_SLOT
J 0
(-3300 4600);
DISPLAY 0.829787 (-3300 4600);
DISPLAY INVISIBLE (-3300 4600);
FORCEPROP 2 LAST CDS_LIB standard
J 0
(-2800 4500);
DISPLAY INVISIBLE (-2800 4500);
FORCEPROP 1 LAST BODY_TYPE PLUMBING
J 2
(-2800 4450);
DISPLAY 0.702128 (-2800 4450);
PAINT GREEN (-2800 4450);
DISPLAY INVISIBLE (-2800 4450);
FORCEPROP 1 LAST HDL_TAP TRUE
J 2
(-3125 4375);
DISPLAY 0.702128 (-3125 4375);
PAINT GREEN (-3125 4375);
DISPLAY INVISIBLE (-3125 4375);
FORCEPROP 1 LAST PATH I352
J 2
(-2798 4500);
DISPLAY 0.872340 (-2798 4500);
PAINT GREEN (-2798 4500);
DISPLAY INVISIBLE (-2798 4500);
FORCEADD TAP..6
R 2
(-2800 4300);
FORCEPROP 3 LASTPIN (-2850 4300) SIG_NAME P5E_CPU1_P0_TX_DN<12>
J 0
(-2840 4310);
DISPLAY 0.659574 (-2840 4310);
PAINT MONO (-2840 4310);
DISPLAY INVISIBLE (-2840 4310);
FORCEPROP 1 LASTPIN (-2850 4300) BN 12
J 2
(-2798 4308);
DISPLAY 0.489362 (-2798 4308);
PAINT MONO (-2798 4308);
FORCEPROP 2 LAST ROOM RISER1
J 0
(-3300 4350);
DISPLAY 0.829787 (-3300 4350);
PAINT RED (-3300 4350);
DISPLAY INVISIBLE (-3300 4350);
FORCEPROP 2 LAST BOM_COST IO_SLOT
J 0
(-3300 4400);
DISPLAY 0.829787 (-3300 4400);
DISPLAY INVISIBLE (-3300 4400);
FORCEPROP 2 LAST CDS_LIB standard
J 0
(-2800 4300);
DISPLAY INVISIBLE (-2800 4300);
FORCEPROP 1 LAST BODY_TYPE PLUMBING
J 2
(-2800 4250);
DISPLAY 0.702128 (-2800 4250);
PAINT GREEN (-2800 4250);
DISPLAY INVISIBLE (-2800 4250);
FORCEPROP 1 LAST HDL_TAP TRUE
J 2
(-3125 4175);
DISPLAY 0.702128 (-3125 4175);
PAINT GREEN (-3125 4175);
DISPLAY INVISIBLE (-3125 4175);
FORCEPROP 1 LAST PATH I353
J 2
(-2798 4300);
DISPLAY 0.872340 (-2798 4300);
PAINT GREEN (-2798 4300);
DISPLAY INVISIBLE (-2798 4300);
FORCEADD TAP..6
R 2
(-2800 4200);
FORCEPROP 3 LASTPIN (-2850 4200) SIG_NAME P5E_CPU1_P0_TX_DN<13>
J 0
(-2840 4210);
DISPLAY 0.659574 (-2840 4210);
PAINT MONO (-2840 4210);
DISPLAY INVISIBLE (-2840 4210);
FORCEPROP 1 LASTPIN (-2850 4200) BN 13
J 2
(-2798 4208);
DISPLAY 0.489362 (-2798 4208);
PAINT MONO (-2798 4208);
FORCEPROP 2 LAST ROOM RISER1
J 0
(-3300 4250);
DISPLAY 0.829787 (-3300 4250);
PAINT RED (-3300 4250);
DISPLAY INVISIBLE (-3300 4250);
FORCEPROP 2 LAST BOM_COST IO_SLOT
J 0
(-3300 4300);
DISPLAY 0.829787 (-3300 4300);
DISPLAY INVISIBLE (-3300 4300);
FORCEPROP 2 LAST CDS_LIB standard
J 0
(-2800 4200);
DISPLAY INVISIBLE (-2800 4200);
FORCEPROP 1 LAST BODY_TYPE PLUMBING
J 2
(-2800 4150);
DISPLAY 0.702128 (-2800 4150);
PAINT GREEN (-2800 4150);
DISPLAY INVISIBLE (-2800 4150);
FORCEPROP 1 LAST HDL_TAP TRUE
J 2
(-3125 4075);
DISPLAY 0.702128 (-3125 4075);
PAINT GREEN (-3125 4075);
DISPLAY INVISIBLE (-3125 4075);
FORCEPROP 1 LAST PATH I354
J 2
(-2798 4200);
DISPLAY 0.872340 (-2798 4200);
PAINT GREEN (-2798 4200);
DISPLAY INVISIBLE (-2798 4200);
FORCEADD TAP..6
R 2
(-2800 4100);
FORCEPROP 3 LASTPIN (-2850 4100) SIG_NAME P5E_CPU1_P0_TX_DN<14>
J 0
(-2840 4110);
DISPLAY 0.659574 (-2840 4110);
PAINT MONO (-2840 4110);
DISPLAY INVISIBLE (-2840 4110);
FORCEPROP 1 LASTPIN (-2850 4100) BN 14
J 2
(-2798 4108);
DISPLAY 0.489362 (-2798 4108);
PAINT MONO (-2798 4108);
FORCEPROP 2 LAST ROOM RISER1
J 0
(-3300 4150);
DISPLAY 0.829787 (-3300 4150);
PAINT RED (-3300 4150);
DISPLAY INVISIBLE (-3300 4150);
FORCEPROP 2 LAST CDS_LIB standard
J 0
(-2800 4100);
DISPLAY INVISIBLE (-2800 4100);
FORCEPROP 2 LAST BOM_COST IO_SLOT
J 0
(-3300 4200);
DISPLAY 0.829787 (-3300 4200);
DISPLAY INVISIBLE (-3300 4200);
FORCEPROP 1 LAST BODY_TYPE PLUMBING
J 2
(-2800 4050);
DISPLAY 0.702128 (-2800 4050);
PAINT GREEN (-2800 4050);
DISPLAY INVISIBLE (-2800 4050);
FORCEPROP 1 LAST HDL_TAP TRUE
J 2
(-3125 3975);
DISPLAY 0.702128 (-3125 3975);
PAINT GREEN (-3125 3975);
DISPLAY INVISIBLE (-3125 3975);
FORCEPROP 1 LAST PATH I355
J 2
(-2798 4100);
DISPLAY 0.872340 (-2798 4100);
PAINT GREEN (-2798 4100);
DISPLAY INVISIBLE (-2798 4100);
FORCEADD TAP..6
R 2
(-2800 4000);
FORCEPROP 3 LASTPIN (-2850 4000) SIG_NAME P5E_CPU1_P0_TX_DN<15>
J 0
(-2840 4010);
DISPLAY 0.659574 (-2840 4010);
PAINT MONO (-2840 4010);
DISPLAY INVISIBLE (-2840 4010);
FORCEPROP 1 LASTPIN (-2850 4000) BN 15
J 2
(-2798 4008);
DISPLAY 0.489362 (-2798 4008);
PAINT MONO (-2798 4008);
FORCEPROP 2 LAST ROOM RISER1
J 0
(-3300 4050);
DISPLAY 0.829787 (-3300 4050);
PAINT RED (-3300 4050);
DISPLAY INVISIBLE (-3300 4050);
FORCEPROP 2 LAST BOM_COST IO_SLOT
J 0
(-3300 4100);
DISPLAY 0.829787 (-3300 4100);
DISPLAY INVISIBLE (-3300 4100);
FORCEPROP 2 LAST CDS_LIB standard
J 0
(-2800 4000);
DISPLAY INVISIBLE (-2800 4000);
FORCEPROP 1 LAST BODY_TYPE PLUMBING
J 2
(-2800 3950);
DISPLAY 0.702128 (-2800 3950);
PAINT GREEN (-2800 3950);
DISPLAY INVISIBLE (-2800 3950);
FORCEPROP 1 LAST HDL_TAP TRUE
J 2
(-3125 3875);
DISPLAY 0.702128 (-3125 3875);
PAINT GREEN (-3125 3875);
DISPLAY INVISIBLE (-3125 3875);
FORCEPROP 1 LAST PATH I356
J 2
(-2798 4000);
DISPLAY 0.872340 (-2798 4000);
PAINT GREEN (-2798 4000);
DISPLAY INVISIBLE (-2798 4000);
FORCEADD QUANTA_TITLE_BLOCK_C..1
(0 0);
FORCEPROP 0 LAST CDS_CON_LAST_MODIFIED Thu Sep 14 16:11:59 2023
J 0
(-1885 15);
DISPLAY INVISIBLE (-1885 15);
FORCEPROP 1 LAST CUSTOM_TXT_CDS <CON_LAST_MODIFIED>
J 0
(-1885 15);
DISPLAY 0.978723 (-1885 15);
FORCEPROP 2 LAST CUSTOM_TXT_CDS <XR_PAGE_TITLE>
J 0
(-7890 5250);
DISPLAY 0.638298 (-7890 5250);
PAINT PINK (-7890 5250);
DISPLAY INVISIBLE (-7890 5250);
FORCEPROP 1 LAST CUSTOM_TXT_CDS <NAME_2>
J 0
(-3175 50);
FORCEPROP 1 LAST CUSTOM_TXT_CDS <NAME_1>
J 0
(-3175 175);
FORCEPROP 1 LAST CUSTOM_TXT_CDS <Q_NUMBER>
J 0
(-1403 103);
DISPLAY 1.212766 (-1403 103);
FORCEPROP 1 LAST CUSTOM_TXT_CDS <Q_PROJ>
J 0
(-2382 102);
DISPLAY 1.212766 (-2382 102);
FORCEPROP 1 LAST CUSTOM_TXT_CDS <Q_REV>
J 0
(-184 103);
DISPLAY 1.212766 (-184 103);
FORCEPROP 1 LAST CUSTOM_TXT_CDS <CON_PAGE_NUM> OF <CON_TOTAL_PAGES>
J 0
(-446 18);
DISPLAY 0.978723 (-446 18);
FORCEPROP 1 LAST Q_TITLE CPU1 PCIE P0/P1
J 0
(-9300 50);
DISPLAY 2.446809 (-9300 50);
PAINT GREEN (-9300 50);
FORCEPROP 2 LAST PAGE_BORDER TRUE
J 0
(-7890 5250);
DISPLAY 0.638298 (-7890 5250);
PAINT PINK (-7890 5250);
DISPLAY INVISIBLE (-7890 5250);
FORCEPROP 1 LAST CDS_LMAN_SYM_OUTLINE -9475,6775,100,-125
J 0
(0 0);
DISPLAY 0.468085 (0 0);
PAINT GREEN (0 0);
DISPLAY INVISIBLE (0 0);
FORCEPROP 2 LAST CDS_LIB pure_quanta
J 0
(0 0);
DISPLAY INVISIBLE (0 0);
FORCEPROP 2 LAST CDS_XR_PAGE_TITLE CR-51 : @T6G_MB_LIB.T6G(SCH_1):PAGE51
J 0
(-7890 5250);
DISPLAY 0.638298 (-7890 5250);
PAINT PINK (-7890 5250);
DISPLAY INVISIBLE (-7890 5250);
FORCEPROP 1 LAST Q_DEPT BU9
J 1
(-3763 49);
DISPLAY 1.957447 (-3763 49);
PAINT GREEN (-3763 49);
DISPLAY INVISIBLE (-3763 49);
FORCEPROP 1 LAST COMMENT_BODY TRUE
J 0
(12 -13);
DISPLAY 0.978723 (12 -13);
PAINT GREEN (12 -13);
DISPLAY INVISIBLE (12 -13);
WIRE 17 -1 (-2825 2175)(-2825 2075);
WIRE 17 -1 (-2825 2275)(-2825 2175);
WIRE 17 -1 (-2825 2075)(-2825 1975);
WIRE 17 -1 (-2825 1975)(-2825 1875);
WIRE 17 -1 (-2825 2375)(-2825 2275);
WIRE 17 -1 (-2825 2475)(-2825 2375);
WIRE 17 -1 (-2825 1875)(-2825 1775);
WIRE 17 -1 (-2825 1775)(-2825 1675);
WIRE 17 -1 (-2825 2575)(-2825 2475);
WIRE 17 -1 (-2825 2675)(-2825 2575);
WIRE 17 -1 (-2825 1675)(-2825 1575);
WIRE 17 -1 (-2825 1575)(-2825 1475);
WIRE 17 -1 (-2825 2775)(-2825 2675);
WIRE 17 -1 (-2825 2875)(-2825 2775);
WIRE 17 -1 (-2825 1475)(-2825 1375);
WIRE 17 -1 (-2825 3075)(-2825 2875);
WIRE 17 -1 (-2825 3075)(-1950 3075);
FORCEPROP 2 LAST SIG_NAME P5E_CPU1_P1_TX_DN<15:0>
J 0
(-2635 3085);
DISPLAY 0.489362 (-2635 3085);
WIRE 17 -1 (-2975 2925)(-2975 2825);
WIRE 17 -1 (-2975 3125)(-2975 2925);
WIRE 17 -1 (-2975 2825)(-2975 2725);
WIRE 17 -1 (-2975 2725)(-2975 2625);
WIRE 17 -1 (-2975 3125)(-1950 3125);
FORCEPROP 2 LAST SIG_NAME P5E_CPU1_P1_TX_DP<15:0>
J 0
(-2635 3135);
DISPLAY 0.489362 (-2635 3135);
WIRE 17 -1 (-2975 2625)(-2975 2525);
WIRE 17 -1 (-2975 2525)(-2975 2425);
WIRE 17 -1 (-2975 2425)(-2975 2325);
WIRE 17 -1 (-2975 2325)(-2975 2225);
WIRE 17 -1 (-2975 2225)(-2975 2125);
WIRE 17 -1 (-2975 2125)(-2975 2025);
WIRE 17 -1 (-2975 2025)(-2975 1925);
WIRE 17 -1 (-2975 1925)(-2975 1825);
WIRE 17 -1 (-2975 1825)(-2975 1725);
WIRE 17 -1 (-2975 1725)(-2975 1625);
WIRE 17 -1 (-2975 1625)(-2975 1525);
WIRE 17 -1 (-2975 1525)(-2975 1425);
WIRE 17 -1 (-6650 4225)(-6650 4325);
WIRE 17 -1 (-6650 4125)(-6650 4225);
WIRE 17 -1 (-6650 4325)(-6650 4425);
WIRE 17 -1 (-6650 4425)(-6650 4525);
WIRE 17 -1 (-6650 4025)(-6650 4125);
WIRE 17 -1 (-6650 4525)(-6650 4625);
WIRE 17 -1 (-6650 4625)(-6650 4725);
WIRE 17 -1 (-6650 4825)(-6650 4725);
WIRE 17 -1 (-6650 4825)(-6650 4925);
WIRE 17 -1 (-6650 4925)(-6650 5025);
WIRE 17 -1 (-6650 5025)(-6650 5125);
WIRE 17 -1 (-6650 5125)(-6650 5225);
WIRE 17 -1 (-6650 5225)(-6650 5325);
WIRE 17 -1 (-6650 5325)(-6650 5425);
WIRE 17 -1 (-6650 5425)(-6650 5525);
WIRE 17 -1 (-6650 5525)(-6650 5725);
WIRE 17 -1 (-6650 5725)(-7500 5725);
FORCEPROP 2 LAST SIG_NAME P5E_CPU1_P0_RX_DN<15:0>
J 0
(-7460 5735);
DISPLAY 0.489362 (-7460 5735);
WIRE 17 -1 (-6500 1925)(-6500 2025);
WIRE 17 -1 (-6500 1825)(-6500 1925);
WIRE 17 -1 (-6500 2025)(-6500 2125);
WIRE 17 -1 (-6500 2125)(-6500 2225);
WIRE 17 -1 (-6500 1725)(-6500 1825);
WIRE 17 -1 (-6500 1625)(-6500 1725);
WIRE 17 -1 (-6500 2225)(-6500 2325);
WIRE 17 -1 (-6500 2325)(-6500 2425);
WIRE 17 -1 (-6500 1525)(-6500 1625);
WIRE 17 -1 (-6500 1425)(-6500 1525);
WIRE 17 -1 (-6500 2425)(-6500 2525);
WIRE 17 -1 (-6500 2525)(-6500 2625);
WIRE 17 -1 (-6500 2625)(-6500 2725);
WIRE 17 -1 (-6500 2725)(-6500 2825);
WIRE 17 -1 (-6500 2825)(-6500 2925);
WIRE 17 -1 (-6500 2925)(-6500 3125);
WIRE 17 -1 (-6500 3125)(-7575 3125);
FORCEPROP 2 LAST SIG_NAME P5E_CPU1_P1_RX_DP<15:0>
J 0
(-7460 3135);
DISPLAY 0.489362 (-7460 3135);
WIRE 17 -1 (-6500 5075)(-6500 5175);
WIRE 17 -1 (-6500 4975)(-6500 5075);
WIRE 17 -1 (-6500 5175)(-6500 5275);
WIRE 17 -1 (-6500 5275)(-6500 5375);
WIRE 17 -1 (-6500 4875)(-6500 4975);
WIRE 17 -1 (-6500 4875)(-6500 4775);
WIRE 17 -1 (-6500 5375)(-6500 5475);
WIRE 17 -1 (-6500 5475)(-6500 5575);
WIRE 17 -1 (-6500 4675)(-6500 4775);
WIRE 17 -1 (-6500 4575)(-6500 4675);
WIRE 17 -1 (-6500 5575)(-6500 5775);
WIRE 17 -1 (-6500 5775)(-7500 5775);
FORCEPROP 2 LAST SIG_NAME P5E_CPU1_P0_RX_DP<15:0>
J 0
(-7460 5785);
DISPLAY 0.489362 (-7460 5785);
WIRE 17 -1 (-6500 4475)(-6500 4575);
WIRE 17 -1 (-6500 4375)(-6500 4475);
WIRE 17 -1 (-6500 4275)(-6500 4375);
WIRE 17 -1 (-6500 4175)(-6500 4275);
WIRE 17 -1 (-6500 4075)(-6500 4175);
WIRE 17 -1 (-2750 5125)(-2750 5025);
WIRE 17 -1 (-2750 5225)(-2750 5125);
WIRE 17 -1 (-2750 5025)(-2750 4925);
WIRE 17 -1 (-2750 4925)(-2750 4825);
WIRE 17 -1 (-2750 5325)(-2750 5225);
WIRE 17 -1 (-2750 5425)(-2750 5325);
WIRE 17 -1 (-2750 4825)(-2750 4725);
WIRE 17 -1 (-2750 4725)(-2750 4625);
WIRE 17 -1 (-2750 5525)(-2750 5425);
WIRE 17 -1 (-2750 5725)(-2750 5525);
WIRE 17 -1 (-2750 4625)(-2750 4525);
WIRE 17 -1 (-2750 4525)(-2750 4425);
WIRE 17 -1 (-2750 5725)(-1875 5725);
FORCEPROP 2 LAST SIG_NAME P5E_CPU1_P0_TX_DN<15:0>
J 0
(-2710 5735);
DISPLAY 0.489362 (-2710 5735);
WIRE 17 -1 (-2900 5075)(-2900 4975);
WIRE 17 -1 (-2900 5175)(-2900 5075);
WIRE 17 -1 (-2900 4975)(-2900 4875);
WIRE 17 -1 (-2900 4875)(-2900 4775);
WIRE 17 -1 (-2900 5275)(-2900 5175);
WIRE 17 -1 (-2900 5375)(-2900 5275);
WIRE 17 -1 (-2900 4775)(-2900 4675);
WIRE 17 -1 (-2900 4675)(-2900 4575);
WIRE 17 -1 (-2900 5475)(-2900 5375);
WIRE 17 -1 (-2900 5575)(-2900 5475);
WIRE 17 -1 (-2900 4575)(-2900 4475);
WIRE 17 -1 (-2900 4475)(-2900 4375);
WIRE 17 -1 (-2900 5775)(-2900 5575);
WIRE 17 -1 (-2900 5775)(-1875 5775);
FORCEPROP 2 LAST SIG_NAME P5E_CPU1_P0_TX_DP<15:0>
J 0
(-2710 5785);
DISPLAY 0.489362 (-2710 5785);
WIRE 17 -1 (-2900 4375)(-2900 4275);
WIRE 17 -1 (-2900 4275)(-2900 4175);
WIRE 17 -1 (-2900 4175)(-2900 4075);
WIRE 17 -1 (-2750 4225)(-2750 4125);
WIRE 17 -1 (-2750 4325)(-2750 4225);
WIRE 17 -1 (-2750 4125)(-2750 4025);
WIRE 17 -1 (-2750 4425)(-2750 4325);
WIRE 17 -1 (-6650 1375)(-6650 1475);
WIRE 17 -1 (-6650 1475)(-6650 1575);
WIRE 17 -1 (-6650 1575)(-6650 1675);
WIRE 17 -1 (-6650 1675)(-6650 1775);
WIRE 17 -1 (-6650 1775)(-6650 1875);
WIRE 17 -1 (-6650 1875)(-6650 1975);
WIRE 17 -1 (-6650 1975)(-6650 2075);
WIRE 17 -1 (-6650 2075)(-6650 2175);
WIRE 17 -1 (-6650 2175)(-6650 2275);
WIRE 17 -1 (-6650 2275)(-6650 2375);
WIRE 17 -1 (-6650 2375)(-6650 2475);
WIRE 17 -1 (-6650 2475)(-6650 2575);
WIRE 17 -1 (-6650 2575)(-6650 2675);
WIRE 17 -1 (-6650 2675)(-6650 2775);
WIRE 17 -1 (-6650 2775)(-6650 2875);
WIRE 17 -1 (-6650 2875)(-6650 3075);
WIRE 17 -1 (-7575 3075)(-6650 3075);
FORCEPROP 2 LAST SIG_NAME P5E_CPU1_P1_RX_DN<15:0>
J 0
(-7460 3085);
DISPLAY 0.489362 (-7460 3085);
WIRE 16 -1 (-6550 2650)(-5950 2650);
WIRE 16 -1 (-3450 2900)(-3075 2900);
WIRE 16 -1 (-6550 2850)(-5950 2850);
WIRE 16 -1 (-6550 1550)(-5950 1550);
WIRE 16 -1 (-6550 1650)(-5950 1650);
WIRE 16 -1 (-6550 1750)(-5950 1750);
WIRE 16 -1 (-6550 1850)(-5950 1850);
WIRE 16 -1 (-6550 1950)(-5950 1950);
WIRE 16 -1 (-6550 2050)(-5950 2050);
WIRE 16 -1 (-6550 2150)(-5950 2150);
WIRE 16 -1 (-6550 2250)(-5950 2250);
WIRE 16 -1 (-6550 2350)(-5950 2350);
WIRE 16 -1 (-6550 2450)(-5950 2450);
WIRE 16 -1 (-6550 2550)(-5950 2550);
WIRE 16 -1 (-6550 2750)(-5950 2750);
WIRE 16 -1 (-6550 1450)(-5950 1450);
WIRE 16 -1 (-6550 1350)(-5950 1350);
WIRE 16 -1 (-6400 1400)(-5950 1400);
WIRE 16 -1 (-6400 1500)(-5950 1500);
WIRE 16 -1 (-6400 1800)(-5950 1800);
WIRE 16 -1 (-6400 2000)(-5950 2000);
WIRE 16 -1 (-6400 2100)(-5950 2100);
WIRE 16 -1 (-6400 2200)(-5950 2200);
WIRE 16 -1 (-6400 2300)(-5950 2300);
WIRE 16 -1 (-6400 2400)(-5950 2400);
WIRE 16 -1 (-6400 2500)(-5950 2500);
WIRE 16 -1 (-6400 2600)(-5950 2600);
WIRE 16 -1 (-6400 2700)(-5950 2700);
WIRE 16 -1 (-6400 2900)(-5950 2900);
WIRE 16 -1 (-6400 2800)(-5950 2800);
WIRE 16 -1 (-3450 2750)(-2925 2750);
WIRE 16 -1 (-3450 4600)(-2850 4600);
WIRE 16 -1 (-3450 4650)(-3000 4650);
WIRE 16 -1 (-3450 4700)(-2850 4700);
WIRE 16 -1 (-6550 4800)(-5950 4800);
WIRE 16 -1 (-6550 5400)(-5950 5400);
WIRE 16 -1 (-6550 5500)(-5950 5500);
WIRE 16 -1 (-3450 4050)(-3000 4050);
WIRE 16 -1 (-6400 5550)(-5950 5550);
WIRE 16 -1 (-6400 4550)(-5950 4550);
WIRE 16 -1 (-6400 4050)(-5950 4050);
WIRE 16 -1 (-6400 4150)(-5950 4150);
WIRE 16 -1 (-6400 4250)(-5950 4250);
WIRE 16 -1 (-6550 4400)(-5950 4400);
WIRE 16 -1 (-6550 4300)(-5950 4300);
WIRE 16 -1 (-6550 4500)(-5950 4500);
WIRE 16 -1 (-6550 4600)(-5950 4600);
WIRE 16 -1 (-6400 4650)(-5950 4650);
WIRE 16 -1 (-6550 4700)(-5950 4700);
WIRE 16 -1 (-6550 4900)(-5950 4900);
WIRE 16 -1 (-6400 4850)(-5950 4850);
WIRE 16 -1 (-6400 4750)(-5950 4750);
WIRE 16 -1 (-3450 4200)(-2850 4200);
WIRE 16 -1 (-3450 4300)(-2850 4300);
WIRE 16 -1 (-3450 4400)(-2850 4400);
WIRE 16 -1 (-3450 4150)(-3000 4150);
WIRE 16 -1 (-3450 4250)(-3000 4250);
WIRE 16 -1 (-3450 4350)(-3000 4350);
WIRE 16 -1 (-3450 4750)(-3000 4750);
WIRE 16 -1 (-3450 4800)(-2850 4800);
WIRE 16 -1 (-6550 5000)(-5950 5000);
WIRE 16 -1 (-6400 4950)(-5950 4950);
WIRE 16 -1 (-6550 5100)(-5950 5100);
WIRE 16 -1 (-3450 4450)(-3000 4450);
WIRE 16 -1 (-3450 4500)(-2850 4500);
WIRE 16 -1 (-3450 4850)(-3000 4850);
WIRE 16 -1 (-3450 4900)(-2850 4900);
WIRE 16 -1 (-3450 5100)(-2850 5100);
WIRE 16 -1 (-3450 5150)(-3000 5150);
WIRE 16 -1 (-3450 5200)(-2850 5200);
WIRE 16 -1 (-3450 5250)(-3000 5250);
WIRE 16 -1 (-3450 5300)(-2850 5300);
WIRE 16 -1 (-3450 5350)(-3000 5350);
WIRE 16 -1 (-3450 5400)(-2850 5400);
WIRE 16 -1 (-3450 5450)(-3000 5450);
WIRE 16 -1 (-3450 4000)(-2850 4000);
WIRE 16 -1 (-3450 4100)(-2850 4100);
WIRE 16 -1 (-3450 5500)(-2850 5500);
WIRE 16 -1 (-3450 5550)(-3000 5550);
WIRE 16 -1 (-6400 5450)(-5950 5450);
WIRE 16 -1 (-6400 5350)(-5950 5350);
WIRE 16 -1 (-6550 5300)(-5950 5300);
WIRE 16 -1 (-6400 5250)(-5950 5250);
WIRE 16 -1 (-6550 5200)(-5950 5200);
WIRE 16 -1 (-6400 5150)(-5950 5150);
WIRE 16 -1 (-3450 5050)(-3000 5050);
WIRE 16 -1 (-3450 4550)(-3000 4550);
WIRE 16 -1 (-3450 4950)(-3000 4950);
WIRE 16 -1 (-3450 5000)(-2850 5000);
WIRE 16 -1 (-6550 4000)(-5950 4000);
WIRE 16 -1 (-6550 4100)(-5950 4100);
WIRE 16 -1 (-6400 4350)(-5950 4350);
WIRE 16 -1 (-6400 4450)(-5950 4450);
WIRE 16 -1 (-6400 5050)(-5950 5050);
WIRE 16 -1 (-6400 1600)(-5950 1600);
WIRE 16 -1 (-6400 1700)(-5950 1700);
WIRE 16 -1 (-6400 1900)(-5950 1900);
WIRE 16 -1 (-6550 4200)(-5950 4200);
WIRE 16 -1 (-3450 1400)(-3075 1400);
WIRE 16 -1 (-3450 1500)(-3075 1500);
WIRE 16 -1 (-3450 1600)(-3075 1600);
WIRE 16 -1 (-3450 1700)(-3075 1700);
WIRE 16 -1 (-3450 1800)(-3075 1800);
WIRE 16 -1 (-3450 1900)(-3075 1900);
WIRE 16 -1 (-3450 2000)(-3075 2000);
WIRE 16 -1 (-3450 1350)(-2925 1350);
WIRE 16 -1 (-3450 1450)(-2925 1450);
WIRE 16 -1 (-3450 1550)(-2925 1550);
WIRE 16 -1 (-3450 1650)(-2925 1650);
WIRE 16 -1 (-3450 1750)(-2925 1750);
WIRE 16 -1 (-3450 1850)(-2925 1850);
WIRE 16 -1 (-3450 1950)(-2925 1950);
WIRE 16 -1 (-3450 2200)(-3075 2200);
WIRE 16 -1 (-3450 2300)(-3075 2300);
WIRE 16 -1 (-3450 2400)(-3075 2400);
WIRE 16 -1 (-3450 2500)(-3075 2500);
WIRE 16 -1 (-3450 2100)(-3075 2100);
WIRE 16 -1 (-3450 2600)(-3075 2600);
WIRE 16 -1 (-3450 2700)(-3075 2700);
WIRE 16 -1 (-3450 2800)(-3075 2800);
WIRE 16 -1 (-3450 2150)(-2925 2150);
WIRE 16 -1 (-3450 2250)(-2925 2250);
WIRE 16 -1 (-3450 2350)(-2925 2350);
WIRE 16 -1 (-3450 2450)(-2925 2450);
WIRE 16 -1 (-3450 2550)(-2925 2550);
WIRE 16 -1 (-3450 2650)(-2925 2650);
WIRE 16 -1 (-3450 2850)(-2925 2850);
WIRE 16 -1 (-3450 2050)(-2925 2050);
FORCENOTE
CPU1 P1[15:0] TO EXAMAX
(-2500 1925) 0;
DISPLAY LEFT (-2500 1925);
DISPLAY 2.000000 (-2500 1925);
FORCENOTE
CPU1 P0[15:0] TO EXAMAX
(-2500 4450) 0;
DISPLAY LEFT (-2500 4450);
DISPLAY 2.000000 (-2500 4450);
QUIT
